(kicad_sch (version 20230121) (generator eeschema)

  (paper "A3")

  (title_block
    (title "Thunderbolt PCIe Adaper")
    (date "2024-07-09")
    (rev "1.0.3")
    (comment 1 "www.antmicro.com")
    (comment 2 "Antmicro Ltd.")
  )

  (junction (at 388.62 162.56) (diameter 0) (color 0 0 0 0)
  )
  (junction (at 288.29 149.86) (diameter 0) (color 0 0 0 0)
  )
  (junction (at 39.37 199.39) (diameter 0) (color 0 0 0 0)
  )
  (junction (at 238.76 165.1) (diameter 0) (color 0 0 0 0)
  )
  (junction (at 146.05 91.44) (diameter 0) (color 0 0 0 0)
  )
  (junction (at 238.76 170.18) (diameter 0) (color 0 0 0 0)
  )
  (junction (at 39.37 250.19) (diameter 0) (color 0 0 0 0)
  )
  (junction (at 179.07 162.56) (diameter 0) (color 0 0 0 0)
  )
  (junction (at 39.37 252.73) (diameter 0) (color 0 0 0 0)
  )
  (junction (at 146.05 88.9) (diameter 0) (color 0 0 0 0)
  )
  (junction (at 299.72 232.41) (diameter 0) (color 0 0 0 0)
  )
  (junction (at 238.76 162.56) (diameter 0) (color 0 0 0 0)
  )
  (junction (at 123.19 217.17) (diameter 0) (color 0 0 0 0)
  )
  (junction (at 299.72 217.17) (diameter 0) (color 0 0 0 0)
  )
  (junction (at 123.19 247.65) (diameter 0) (color 0 0 0 0)
  )
  (junction (at 39.37 196.85) (diameter 0) (color 0 0 0 0)
  )
  (junction (at 39.37 257.81) (diameter 0) (color 0 0 0 0)
  )
  (junction (at 123.19 224.79) (diameter 0) (color 0 0 0 0)
  )
  (junction (at 179.07 165.1) (diameter 0) (color 0 0 0 0)
  )
  (junction (at 123.19 240.03) (diameter 0) (color 0 0 0 0)
  )
  (junction (at 288.29 144.78) (diameter 0) (color 0 0 0 0)
  )
  (junction (at 52.07 88.9) (diameter 0) (color 0 0 0 0)
  )
  (junction (at 335.28 39.37) (diameter 0) (color 0 0 0 0)
  )
  (junction (at 306.07 217.17) (diameter 0) (color 0 0 0 0)
  )
  (junction (at 55.88 86.36) (diameter 0) (color 0 0 0 0)
  )
  (junction (at 313.69 242.57) (diameter 0) (color 0 0 0 0)
  )
  (junction (at 123.19 214.63) (diameter 0) (color 0 0 0 0)
  )
  (junction (at 123.19 245.11) (diameter 0) (color 0 0 0 0)
  )
  (junction (at 266.7 240.03) (diameter 0) (color 0 0 0 0)
  )
  (junction (at 123.19 222.25) (diameter 0) (color 0 0 0 0)
  )
  (junction (at 137.16 242.57) (diameter 0) (color 0 0 0 0)
  )
  (junction (at 388.62 151.13) (diameter 0) (color 0 0 0 0)
  )
  (junction (at 123.19 219.71) (diameter 0) (color 0 0 0 0)
  )
  (junction (at 288.29 147.32) (diameter 0) (color 0 0 0 0)
  )
  (junction (at 146.05 96.52) (diameter 0) (color 0 0 0 0)
  )
  (junction (at 373.38 147.32) (diameter 0) (color 0 0 0 0)
  )
  (junction (at 317.5 49.53) (diameter 0) (color 0 0 0 0)
  )
  (junction (at 317.5 60.96) (diameter 0) (color 0 0 0 0)
  )
  (junction (at 123.19 196.85) (diameter 0) (color 0 0 0 0)
  )
  (junction (at 179.07 172.72) (diameter 0) (color 0 0 0 0)
  )
  (junction (at 179.07 170.18) (diameter 0) (color 0 0 0 0)
  )
  (junction (at 266.7 231.14) (diameter 0) (color 0 0 0 0)
  )

  (no_connect (at 52.07 217.17))
  (no_connect (at 132.08 55.88))
  (no_connect (at 107.95 171.45))
  (no_connect (at 236.22 149.86))
  (no_connect (at 107.95 156.21))
  (no_connect (at 52.07 224.79))
  (no_connect (at 52.07 214.63))
  (no_connect (at 236.22 157.48))
  (no_connect (at 132.08 43.18))
  (no_connect (at 180.34 144.78))
  (no_connect (at 132.08 81.28))
  (no_connect (at 132.08 63.5))
  (no_connect (at 107.95 161.29))
  (no_connect (at 52.07 184.15))
  (no_connect (at 107.95 184.15))
  (no_connect (at 132.08 78.74))
  (no_connect (at 52.07 207.01))
  (no_connect (at 52.07 232.41))
  (no_connect (at 52.07 168.91))
  (no_connect (at 180.34 147.32))
  (no_connect (at 52.07 153.67))
  (no_connect (at 52.07 179.07))
  (no_connect (at 132.08 71.12))
  (no_connect (at 132.08 50.8))
  (no_connect (at 107.95 179.07))
  (no_connect (at 52.07 161.29))
  (no_connect (at 236.22 152.4))
  (no_connect (at 52.07 186.69))
  (no_connect (at 107.95 176.53))
  (no_connect (at 52.07 176.53))
  (no_connect (at 107.95 163.83))
  (no_connect (at 132.08 40.64))
  (no_connect (at 52.07 222.25))
  (no_connect (at 52.07 163.83))
  (no_connect (at 52.07 229.87))
  (no_connect (at 132.08 48.26))
  (no_connect (at 107.95 168.91))
  (no_connect (at 52.07 240.03))
  (no_connect (at 52.07 237.49))
  (no_connect (at 107.95 186.69))
  (no_connect (at 107.95 153.67))
  (no_connect (at 52.07 171.45))
  (no_connect (at 132.08 73.66))
  (no_connect (at 132.08 66.04))
  (no_connect (at 52.07 156.21))
  (no_connect (at 132.08 58.42))
  (no_connect (at 52.07 209.55))
  (no_connect (at 180.34 152.4))

  (wire (pts (xy 146.05 86.36) (xy 146.05 88.9))
    (stroke (width 0) (type default))
  )
  (wire (pts (xy 264.16 64.77) (xy 278.13 64.77))
    (stroke (width 0) (type default))
  )
  (wire (pts (xy 107.95 214.63) (xy 111.76 214.63))
    (stroke (width 0) (type default))
  )
  (wire (pts (xy 264.16 72.39) (xy 278.13 72.39))
    (stroke (width 0) (type default))
  )
  (wire (pts (xy 39.37 196.85) (xy 43.18 196.85))
    (stroke (width 0) (type default))
  )
  (wire (pts (xy 266.7 231.14) (xy 266.7 228.6))
    (stroke (width 0) (type default))
  )
  (wire (pts (xy 237.49 69.85) (xy 265.43 69.85))
    (stroke (width 0) (type default))
  )
  (wire (pts (xy 238.76 165.1) (xy 238.76 170.18))
    (stroke (width 0) (type default))
  )
  (wire (pts (xy 107.95 247.65) (xy 111.76 247.65))
    (stroke (width 0) (type default))
  )
  (wire (pts (xy 266.7 240.03) (xy 266.7 242.57))
    (stroke (width 0) (type default))
  )
  (wire (pts (xy 264.16 49.53) (xy 278.13 49.53))
    (stroke (width 0) (type default))
  )
  (wire (pts (xy 107.95 217.17) (xy 111.76 217.17))
    (stroke (width 0) (type default))
  )
  (wire (pts (xy 146.05 96.52) (xy 146.05 100.33))
    (stroke (width 0) (type default))
  )
  (wire (pts (xy 107.95 212.09) (xy 111.76 212.09))
    (stroke (width 0) (type default))
  )
  (wire (pts (xy 287.02 144.78) (xy 288.29 144.78))
    (stroke (width 0) (type default))
  )
  (wire (pts (xy 224.79 237.49) (xy 238.76 237.49))
    (stroke (width 0) (type default))
  )
  (wire (pts (xy 55.88 66.04) (xy 76.2 66.04))
    (stroke (width 0) (type default))
  )
  (wire (pts (xy 123.19 219.71) (xy 123.19 217.17))
    (stroke (width 0) (type default))
  )
  (wire (pts (xy 116.84 247.65) (xy 123.19 247.65))
    (stroke (width 0) (type default))
  )
  (wire (pts (xy 264.16 57.15) (xy 278.13 57.15))
    (stroke (width 0) (type default))
  )
  (wire (pts (xy 224.79 234.95) (xy 238.76 234.95))
    (stroke (width 0) (type default))
  )
  (wire (pts (xy 48.26 257.81) (xy 52.07 257.81))
    (stroke (width 0) (type default))
  )
  (wire (pts (xy 359.41 165.1) (xy 358.14 165.1))
    (stroke (width 0) (type default))
  )
  (wire (pts (xy 107.95 224.79) (xy 111.76 224.79))
    (stroke (width 0) (type default))
  )
  (wire (pts (xy 179.07 162.56) (xy 180.34 162.56))
    (stroke (width 0) (type default))
  )
  (wire (pts (xy 394.97 156.21) (xy 393.7 156.21))
    (stroke (width 0) (type default))
  )
  (wire (pts (xy 107.95 219.71) (xy 111.76 219.71))
    (stroke (width 0) (type default))
  )
  (wire (pts (xy 313.69 217.17) (xy 313.69 219.71))
    (stroke (width 0) (type default))
  )
  (wire (pts (xy 172.72 49.53) (xy 181.61 49.53))
    (stroke (width 0) (type default))
  )
  (wire (pts (xy 179.07 157.48) (xy 180.34 157.48))
    (stroke (width 0) (type default))
  )
  (wire (pts (xy 299.72 217.17) (xy 299.72 215.9))
    (stroke (width 0) (type default))
  )
  (wire (pts (xy 294.64 240.03) (xy 326.39 240.03))
    (stroke (width 0) (type default))
  )
  (wire (pts (xy 123.19 226.06) (xy 123.19 224.79))
    (stroke (width 0) (type default))
  )
  (wire (pts (xy 48.26 196.85) (xy 52.07 196.85))
    (stroke (width 0) (type default))
  )
  (wire (pts (xy 270.51 62.23) (xy 278.13 62.23))
    (stroke (width 0) (type default))
  )
  (wire (pts (xy 231.14 212.09) (xy 232.41 212.09))
    (stroke (width 0) (type default))
  )
  (wire (pts (xy 270.51 54.61) (xy 278.13 54.61))
    (stroke (width 0) (type default))
  )
  (wire (pts (xy 397.51 151.13) (xy 398.78 151.13))
    (stroke (width 0) (type default))
  )
  (wire (pts (xy 313.69 242.57) (xy 326.39 242.57))
    (stroke (width 0) (type default))
  )
  (wire (pts (xy 39.37 191.77) (xy 43.18 191.77))
    (stroke (width 0) (type default))
  )
  (wire (pts (xy 306.07 224.79) (xy 306.07 234.95))
    (stroke (width 0) (type default))
  )
  (wire (pts (xy 358.14 147.32) (xy 361.95 147.32))
    (stroke (width 0) (type default))
  )
  (wire (pts (xy 307.34 49.53) (xy 309.88 49.53))
    (stroke (width 0) (type default))
  )
  (wire (pts (xy 39.37 259.08) (xy 39.37 257.81))
    (stroke (width 0) (type default))
  )
  (wire (pts (xy 358.14 149.86) (xy 359.41 149.86))
    (stroke (width 0) (type default))
  )
  (wire (pts (xy 66.04 50.8) (xy 76.2 50.8))
    (stroke (width 0) (type default))
  )
  (wire (pts (xy 123.19 198.12) (xy 123.19 196.85))
    (stroke (width 0) (type default))
  )
  (wire (pts (xy 179.07 157.48) (xy 179.07 162.56))
    (stroke (width 0) (type default))
  )
  (wire (pts (xy 123.19 224.79) (xy 123.19 222.25))
    (stroke (width 0) (type default))
  )
  (wire (pts (xy 33.02 66.04) (xy 50.8 66.04))
    (stroke (width 0) (type default))
  )
  (wire (pts (xy 49.53 71.12) (xy 76.2 71.12))
    (stroke (width 0) (type default))
  )
  (wire (pts (xy 294.64 229.87) (xy 326.39 229.87))
    (stroke (width 0) (type default))
  )
  (wire (pts (xy 298.45 149.86) (xy 302.26 149.86))
    (stroke (width 0) (type default))
  )
  (wire (pts (xy 330.2 49.53) (xy 330.2 53.34))
    (stroke (width 0) (type default))
  )
  (wire (pts (xy 177.8 85.09) (xy 181.61 85.09))
    (stroke (width 0) (type default))
  )
  (wire (pts (xy 49.53 55.88) (xy 76.2 55.88))
    (stroke (width 0) (type default))
  )
  (wire (pts (xy 40.64 86.36) (xy 55.88 86.36))
    (stroke (width 0) (type default))
  )
  (wire (pts (xy 107.95 204.47) (xy 116.84 204.47))
    (stroke (width 0) (type default))
  )
  (wire (pts (xy 181.61 77.47) (xy 165.1 77.47))
    (stroke (width 0) (type default))
  )
  (wire (pts (xy 299.72 217.17) (xy 299.72 219.71))
    (stroke (width 0) (type default))
  )
  (wire (pts (xy 52.07 88.9) (xy 52.07 92.71))
    (stroke (width 0) (type default))
  )
  (wire (pts (xy 299.72 157.48) (xy 299.72 161.29))
    (stroke (width 0) (type default))
  )
  (wire (pts (xy 172.72 69.85) (xy 181.61 69.85))
    (stroke (width 0) (type default))
  )
  (wire (pts (xy 237.49 62.23) (xy 265.43 62.23))
    (stroke (width 0) (type default))
  )
  (wire (pts (xy 48.26 245.11) (xy 52.07 245.11))
    (stroke (width 0) (type default))
  )
  (wire (pts (xy 39.37 250.19) (xy 43.18 250.19))
    (stroke (width 0) (type default))
  )
  (wire (pts (xy 179.07 165.1) (xy 179.07 170.18))
    (stroke (width 0) (type default))
  )
  (wire (pts (xy 107.95 240.03) (xy 111.76 240.03))
    (stroke (width 0) (type default))
  )
  (wire (pts (xy 367.03 144.78) (xy 373.38 144.78))
    (stroke (width 0) (type default))
  )
  (wire (pts (xy 266.7 240.03) (xy 269.24 240.03))
    (stroke (width 0) (type default))
  )
  (wire (pts (xy 172.72 72.39) (xy 181.61 72.39))
    (stroke (width 0) (type default))
  )
  (wire (pts (xy 132.08 88.9) (xy 134.62 88.9))
    (stroke (width 0) (type default))
  )
  (wire (pts (xy 358.14 162.56) (xy 359.41 162.56))
    (stroke (width 0) (type default))
  )
  (wire (pts (xy 224.79 240.03) (xy 238.76 240.03))
    (stroke (width 0) (type default))
  )
  (wire (pts (xy 238.76 170.18) (xy 238.76 172.72))
    (stroke (width 0) (type default))
  )
  (wire (pts (xy 132.08 91.44) (xy 134.62 91.44))
    (stroke (width 0) (type default))
  )
  (wire (pts (xy 237.49 49.53) (xy 259.08 49.53))
    (stroke (width 0) (type default))
  )
  (wire (pts (xy 107.95 209.55) (xy 116.84 209.55))
    (stroke (width 0) (type default))
  )
  (wire (pts (xy 52.07 97.79) (xy 52.07 100.33))
    (stroke (width 0) (type default))
  )
  (wire (pts (xy 236.22 144.78) (xy 238.76 144.78))
    (stroke (width 0) (type default))
  )
  (wire (pts (xy 172.72 64.77) (xy 181.61 64.77))
    (stroke (width 0) (type default))
  )
  (wire (pts (xy 116.84 222.25) (xy 123.19 222.25))
    (stroke (width 0) (type default))
  )
  (wire (pts (xy 73.66 96.52) (xy 76.2 96.52))
    (stroke (width 0) (type default))
  )
  (wire (pts (xy 116.84 234.95) (xy 121.92 234.95))
    (stroke (width 0) (type default))
  )
  (wire (pts (xy 288.29 152.4) (xy 293.37 152.4))
    (stroke (width 0) (type default))
  )
  (wire (pts (xy 39.37 257.81) (xy 43.18 257.81))
    (stroke (width 0) (type default))
  )
  (wire (pts (xy 66.04 43.18) (xy 76.2 43.18))
    (stroke (width 0) (type default))
  )
  (wire (pts (xy 39.37 196.85) (xy 39.37 191.77))
    (stroke (width 0) (type default))
  )
  (wire (pts (xy 48.26 252.73) (xy 52.07 252.73))
    (stroke (width 0) (type default))
  )
  (wire (pts (xy 358.14 144.78) (xy 361.95 144.78))
    (stroke (width 0) (type default))
  )
  (wire (pts (xy 335.28 39.37) (xy 335.28 40.64))
    (stroke (width 0) (type default))
  )
  (wire (pts (xy 39.37 245.11) (xy 43.18 245.11))
    (stroke (width 0) (type default))
  )
  (wire (pts (xy 39.37 199.39) (xy 39.37 196.85))
    (stroke (width 0) (type default))
  )
  (wire (pts (xy 240.03 80.01) (xy 237.49 80.01))
    (stroke (width 0) (type default))
  )
  (wire (pts (xy 48.26 199.39) (xy 52.07 199.39))
    (stroke (width 0) (type default))
  )
  (wire (pts (xy 317.5 60.96) (xy 330.2 60.96))
    (stroke (width 0) (type default))
  )
  (wire (pts (xy 49.53 63.5) (xy 76.2 63.5))
    (stroke (width 0) (type default))
  )
  (wire (pts (xy 139.7 88.9) (xy 146.05 88.9))
    (stroke (width 0) (type default))
  )
  (wire (pts (xy 116.84 240.03) (xy 123.19 240.03))
    (stroke (width 0) (type default))
  )
  (wire (pts (xy 238.76 144.78) (xy 238.76 162.56))
    (stroke (width 0) (type default))
  )
  (wire (pts (xy 237.49 57.15) (xy 259.08 57.15))
    (stroke (width 0) (type default))
  )
  (wire (pts (xy 288.29 147.32) (xy 288.29 144.78))
    (stroke (width 0) (type default))
  )
  (wire (pts (xy 123.19 240.03) (xy 123.19 245.11))
    (stroke (width 0) (type default))
  )
  (wire (pts (xy 55.88 86.36) (xy 55.88 92.71))
    (stroke (width 0) (type default))
  )
  (wire (pts (xy 33.02 63.5) (xy 44.45 63.5))
    (stroke (width 0) (type default))
  )
  (wire (pts (xy 288.29 149.86) (xy 288.29 147.32))
    (stroke (width 0) (type default))
  )
  (wire (pts (xy 181.61 80.01) (xy 165.1 80.01))
    (stroke (width 0) (type default))
  )
  (wire (pts (xy 264.16 231.14) (xy 266.7 231.14))
    (stroke (width 0) (type default))
  )
  (wire (pts (xy 172.72 57.15) (xy 181.61 57.15))
    (stroke (width 0) (type default))
  )
  (wire (pts (xy 377.19 162.56) (xy 388.62 162.56))
    (stroke (width 0) (type default))
  )
  (wire (pts (xy 116.84 196.85) (xy 123.19 196.85))
    (stroke (width 0) (type default))
  )
  (wire (pts (xy 107.95 207.01) (xy 116.84 207.01))
    (stroke (width 0) (type default))
  )
  (wire (pts (xy 377.19 157.48) (xy 377.19 162.56))
    (stroke (width 0) (type default))
  )
  (wire (pts (xy 307.34 60.96) (xy 309.88 60.96))
    (stroke (width 0) (type default))
  )
  (wire (pts (xy 340.36 39.37) (xy 340.36 50.8))
    (stroke (width 0) (type default))
  )
  (wire (pts (xy 270.51 46.99) (xy 278.13 46.99))
    (stroke (width 0) (type default))
  )
  (wire (pts (xy 330.2 55.88) (xy 341.63 55.88))
    (stroke (width 0) (type default))
  )
  (wire (pts (xy 179.07 162.56) (xy 179.07 165.1))
    (stroke (width 0) (type default))
  )
  (wire (pts (xy 62.23 78.74) (xy 76.2 78.74))
    (stroke (width 0) (type default))
  )
  (wire (pts (xy 365.76 50.8) (xy 382.27 50.8))
    (stroke (width 0) (type default))
  )
  (wire (pts (xy 306.07 217.17) (xy 306.07 219.71))
    (stroke (width 0) (type default))
  )
  (wire (pts (xy 294.64 242.57) (xy 313.69 242.57))
    (stroke (width 0) (type default))
  )
  (wire (pts (xy 179.07 170.18) (xy 180.34 170.18))
    (stroke (width 0) (type default))
  )
  (wire (pts (xy 116.84 214.63) (xy 123.19 214.63))
    (stroke (width 0) (type default))
  )
  (wire (pts (xy 33.02 73.66) (xy 50.8 73.66))
    (stroke (width 0) (type default))
  )
  (wire (pts (xy 288.29 152.4) (xy 288.29 149.86))
    (stroke (width 0) (type default))
  )
  (wire (pts (xy 139.7 96.52) (xy 146.05 96.52))
    (stroke (width 0) (type default))
  )
  (wire (pts (xy 33.02 58.42) (xy 50.8 58.42))
    (stroke (width 0) (type default))
  )
  (wire (pts (xy 179.07 172.72) (xy 179.07 175.26))
    (stroke (width 0) (type default))
  )
  (wire (pts (xy 299.72 224.79) (xy 299.72 232.41))
    (stroke (width 0) (type default))
  )
  (wire (pts (xy 66.04 40.64) (xy 76.2 40.64))
    (stroke (width 0) (type default))
  )
  (wire (pts (xy 146.05 88.9) (xy 146.05 91.44))
    (stroke (width 0) (type default))
  )
  (wire (pts (xy 359.41 170.18) (xy 358.14 170.18))
    (stroke (width 0) (type default))
  )
  (wire (pts (xy 116.84 224.79) (xy 123.19 224.79))
    (stroke (width 0) (type default))
  )
  (wire (pts (xy 341.63 50.8) (xy 340.36 50.8))
    (stroke (width 0) (type default))
  )
  (wire (pts (xy 224.79 242.57) (xy 238.76 242.57))
    (stroke (width 0) (type default))
  )
  (wire (pts (xy 358.14 157.48) (xy 377.19 157.48))
    (stroke (width 0) (type default))
  )
  (wire (pts (xy 232.41 212.09) (xy 232.41 213.36))
    (stroke (width 0) (type default))
  )
  (wire (pts (xy 236.22 162.56) (xy 238.76 162.56))
    (stroke (width 0) (type default))
  )
  (wire (pts (xy 236.22 170.18) (xy 238.76 170.18))
    (stroke (width 0) (type default))
  )
  (wire (pts (xy 246.38 85.09) (xy 248.92 85.09))
    (stroke (width 0) (type default))
  )
  (wire (pts (xy 123.19 237.49) (xy 123.19 240.03))
    (stroke (width 0) (type default))
  )
  (wire (pts (xy 55.88 73.66) (xy 76.2 73.66))
    (stroke (width 0) (type default))
  )
  (wire (pts (xy 172.72 62.23) (xy 181.61 62.23))
    (stroke (width 0) (type default))
  )
  (wire (pts (xy 146.05 91.44) (xy 146.05 96.52))
    (stroke (width 0) (type default))
  )
  (wire (pts (xy 365.76 55.88) (xy 382.27 55.88))
    (stroke (width 0) (type default))
  )
  (wire (pts (xy 358.14 154.94) (xy 377.19 154.94))
    (stroke (width 0) (type default))
  )
  (wire (pts (xy 237.49 64.77) (xy 259.08 64.77))
    (stroke (width 0) (type default))
  )
  (wire (pts (xy 294.64 234.95) (xy 306.07 234.95))
    (stroke (width 0) (type default))
  )
  (wire (pts (xy 33.02 55.88) (xy 44.45 55.88))
    (stroke (width 0) (type default))
  )
  (wire (pts (xy 123.19 196.85) (xy 123.19 191.77))
    (stroke (width 0) (type default))
  )
  (wire (pts (xy 224.79 229.87) (xy 238.76 229.87))
    (stroke (width 0) (type default))
  )
  (wire (pts (xy 232.41 218.44) (xy 232.41 219.71))
    (stroke (width 0) (type default))
  )
  (wire (pts (xy 170.18 85.09) (xy 172.72 85.09))
    (stroke (width 0) (type default))
  )
  (wire (pts (xy 331.47 39.37) (xy 335.28 39.37))
    (stroke (width 0) (type default))
  )
  (wire (pts (xy 137.16 242.57) (xy 138.43 242.57))
    (stroke (width 0) (type default))
  )
  (wire (pts (xy 377.19 154.94) (xy 377.19 151.13))
    (stroke (width 0) (type default))
  )
  (wire (pts (xy 311.15 54.61) (xy 312.42 54.61))
    (stroke (width 0) (type default))
  )
  (wire (pts (xy 116.84 245.11) (xy 123.19 245.11))
    (stroke (width 0) (type default))
  )
  (wire (pts (xy 236.22 165.1) (xy 238.76 165.1))
    (stroke (width 0) (type default))
  )
  (wire (pts (xy 314.96 49.53) (xy 317.5 49.53))
    (stroke (width 0) (type default))
  )
  (wire (pts (xy 266.7 231.14) (xy 269.24 231.14))
    (stroke (width 0) (type default))
  )
  (wire (pts (xy 179.07 172.72) (xy 180.34 172.72))
    (stroke (width 0) (type default))
  )
  (wire (pts (xy 107.95 245.11) (xy 111.76 245.11))
    (stroke (width 0) (type default))
  )
  (wire (pts (xy 172.72 46.99) (xy 181.61 46.99))
    (stroke (width 0) (type default))
  )
  (wire (pts (xy 123.19 214.63) (xy 123.19 212.09))
    (stroke (width 0) (type default))
  )
  (wire (pts (xy 330.2 60.96) (xy 330.2 55.88))
    (stroke (width 0) (type default))
  )
  (wire (pts (xy 248.92 85.09) (xy 248.92 86.36))
    (stroke (width 0) (type default))
  )
  (wire (pts (xy 107.95 191.77) (xy 111.76 191.77))
    (stroke (width 0) (type default))
  )
  (wire (pts (xy 52.07 88.9) (xy 76.2 88.9))
    (stroke (width 0) (type default))
  )
  (wire (pts (xy 294.64 237.49) (xy 317.5 237.49))
    (stroke (width 0) (type default))
  )
  (wire (pts (xy 388.62 160.02) (xy 388.62 162.56))
    (stroke (width 0) (type default))
  )
  (wire (pts (xy 330.2 53.34) (xy 341.63 53.34))
    (stroke (width 0) (type default))
  )
  (wire (pts (xy 388.62 151.13) (xy 392.43 151.13))
    (stroke (width 0) (type default))
  )
  (wire (pts (xy 313.69 224.79) (xy 313.69 242.57))
    (stroke (width 0) (type default))
  )
  (wire (pts (xy 139.7 91.44) (xy 146.05 91.44))
    (stroke (width 0) (type default))
  )
  (wire (pts (xy 299.72 232.41) (xy 326.39 232.41))
    (stroke (width 0) (type default))
  )
  (wire (pts (xy 299.72 170.18) (xy 302.26 170.18))
    (stroke (width 0) (type default))
  )
  (wire (pts (xy 107.95 234.95) (xy 111.76 234.95))
    (stroke (width 0) (type default))
  )
  (wire (pts (xy 314.96 60.96) (xy 317.5 60.96))
    (stroke (width 0) (type default))
  )
  (wire (pts (xy 335.28 39.37) (xy 340.36 39.37))
    (stroke (width 0) (type default))
  )
  (wire (pts (xy 264.16 240.03) (xy 266.7 240.03))
    (stroke (width 0) (type default))
  )
  (wire (pts (xy 359.41 167.64) (xy 358.14 167.64))
    (stroke (width 0) (type default))
  )
  (wire (pts (xy 39.37 252.73) (xy 43.18 252.73))
    (stroke (width 0) (type default))
  )
  (wire (pts (xy 48.26 250.19) (xy 52.07 250.19))
    (stroke (width 0) (type default))
  )
  (wire (pts (xy 137.16 238.76) (xy 137.16 242.57))
    (stroke (width 0) (type default))
  )
  (wire (pts (xy 107.95 232.41) (xy 121.92 232.41))
    (stroke (width 0) (type default))
  )
  (wire (pts (xy 116.84 191.77) (xy 123.19 191.77))
    (stroke (width 0) (type default))
  )
  (wire (pts (xy 55.88 97.79) (xy 55.88 100.33))
    (stroke (width 0) (type default))
  )
  (wire (pts (xy 299.72 166.37) (xy 299.72 170.18))
    (stroke (width 0) (type default))
  )
  (wire (pts (xy 317.5 58.42) (xy 317.5 60.96))
    (stroke (width 0) (type default))
  )
  (wire (pts (xy 48.26 191.77) (xy 52.07 191.77))
    (stroke (width 0) (type default))
  )
  (wire (pts (xy 388.62 162.56) (xy 392.43 162.56))
    (stroke (width 0) (type default))
  )
  (wire (pts (xy 55.88 58.42) (xy 76.2 58.42))
    (stroke (width 0) (type default))
  )
  (wire (pts (xy 107.95 196.85) (xy 111.76 196.85))
    (stroke (width 0) (type default))
  )
  (wire (pts (xy 39.37 252.73) (xy 39.37 250.19))
    (stroke (width 0) (type default))
  )
  (wire (pts (xy 107.95 242.57) (xy 137.16 242.57))
    (stroke (width 0) (type default))
  )
  (wire (pts (xy 172.72 54.61) (xy 181.61 54.61))
    (stroke (width 0) (type default))
  )
  (wire (pts (xy 288.29 149.86) (xy 293.37 149.86))
    (stroke (width 0) (type default))
  )
  (wire (pts (xy 365.76 58.42) (xy 382.27 58.42))
    (stroke (width 0) (type default))
  )
  (wire (pts (xy 322.58 237.49) (xy 326.39 237.49))
    (stroke (width 0) (type default))
  )
  (wire (pts (xy 123.19 217.17) (xy 123.19 214.63))
    (stroke (width 0) (type default))
  )
  (wire (pts (xy 33.02 71.12) (xy 44.45 71.12))
    (stroke (width 0) (type default))
  )
  (wire (pts (xy 317.5 49.53) (xy 330.2 49.53))
    (stroke (width 0) (type default))
  )
  (wire (pts (xy 66.04 96.52) (xy 68.58 96.52))
    (stroke (width 0) (type default))
  )
  (wire (pts (xy 40.64 88.9) (xy 52.07 88.9))
    (stroke (width 0) (type default))
  )
  (wire (pts (xy 237.49 46.99) (xy 265.43 46.99))
    (stroke (width 0) (type default))
  )
  (wire (pts (xy 72.39 91.44) (xy 76.2 91.44))
    (stroke (width 0) (type default))
  )
  (wire (pts (xy 317.5 50.8) (xy 317.5 49.53))
    (stroke (width 0) (type default))
  )
  (wire (pts (xy 62.23 81.28) (xy 76.2 81.28))
    (stroke (width 0) (type default))
  )
  (wire (pts (xy 179.07 165.1) (xy 180.34 165.1))
    (stroke (width 0) (type default))
  )
  (wire (pts (xy 39.37 245.11) (xy 39.37 250.19))
    (stroke (width 0) (type default))
  )
  (wire (pts (xy 288.29 147.32) (xy 293.37 147.32))
    (stroke (width 0) (type default))
  )
  (wire (pts (xy 123.19 245.11) (xy 123.19 247.65))
    (stroke (width 0) (type default))
  )
  (wire (pts (xy 306.07 217.17) (xy 313.69 217.17))
    (stroke (width 0) (type default))
  )
  (wire (pts (xy 224.79 232.41) (xy 238.76 232.41))
    (stroke (width 0) (type default))
  )
  (wire (pts (xy 132.08 96.52) (xy 134.62 96.52))
    (stroke (width 0) (type default))
  )
  (wire (pts (xy 116.84 219.71) (xy 123.19 219.71))
    (stroke (width 0) (type default))
  )
  (wire (pts (xy 238.76 162.56) (xy 238.76 165.1))
    (stroke (width 0) (type default))
  )
  (wire (pts (xy 66.04 48.26) (xy 76.2 48.26))
    (stroke (width 0) (type default))
  )
  (wire (pts (xy 116.84 212.09) (xy 123.19 212.09))
    (stroke (width 0) (type default))
  )
  (wire (pts (xy 298.45 147.32) (xy 302.26 147.32))
    (stroke (width 0) (type default))
  )
  (wire (pts (xy 66.04 100.33) (xy 66.04 96.52))
    (stroke (width 0) (type default))
  )
  (wire (pts (xy 298.45 152.4) (xy 302.26 152.4))
    (stroke (width 0) (type default))
  )
  (wire (pts (xy 373.38 147.32) (xy 373.38 149.86))
    (stroke (width 0) (type default))
  )
  (wire (pts (xy 39.37 257.81) (xy 39.37 252.73))
    (stroke (width 0) (type default))
  )
  (wire (pts (xy 377.19 151.13) (xy 388.62 151.13))
    (stroke (width 0) (type default))
  )
  (wire (pts (xy 288.29 144.78) (xy 293.37 144.78))
    (stroke (width 0) (type default))
  )
  (wire (pts (xy 123.19 247.65) (xy 123.19 248.92))
    (stroke (width 0) (type default))
  )
  (wire (pts (xy 299.72 217.17) (xy 306.07 217.17))
    (stroke (width 0) (type default))
  )
  (wire (pts (xy 39.37 199.39) (xy 43.18 199.39))
    (stroke (width 0) (type default))
  )
  (wire (pts (xy 397.51 162.56) (xy 398.78 162.56))
    (stroke (width 0) (type default))
  )
  (wire (pts (xy 365.76 53.34) (xy 382.27 53.34))
    (stroke (width 0) (type default))
  )
  (wire (pts (xy 55.88 86.36) (xy 76.2 86.36))
    (stroke (width 0) (type default))
  )
  (wire (pts (xy 179.07 170.18) (xy 179.07 172.72))
    (stroke (width 0) (type default))
  )
  (wire (pts (xy 388.62 152.4) (xy 388.62 151.13))
    (stroke (width 0) (type default))
  )
  (wire (pts (xy 107.95 222.25) (xy 111.76 222.25))
    (stroke (width 0) (type default))
  )
  (wire (pts (xy 237.49 72.39) (xy 259.08 72.39))
    (stroke (width 0) (type default))
  )
  (wire (pts (xy 294.64 232.41) (xy 299.72 232.41))
    (stroke (width 0) (type default))
  )
  (wire (pts (xy 341.63 58.42) (xy 340.36 58.42))
    (stroke (width 0) (type default))
  )
  (wire (pts (xy 270.51 69.85) (xy 278.13 69.85))
    (stroke (width 0) (type default))
  )
  (wire (pts (xy 132.08 86.36) (xy 134.62 86.36))
    (stroke (width 0) (type default))
  )
  (wire (pts (xy 116.84 237.49) (xy 123.19 237.49))
    (stroke (width 0) (type default))
  )
  (wire (pts (xy 237.49 85.09) (xy 241.3 85.09))
    (stroke (width 0) (type default))
  )
  (wire (pts (xy 237.49 54.61) (xy 265.43 54.61))
    (stroke (width 0) (type default))
  )
  (wire (pts (xy 123.19 222.25) (xy 123.19 219.71))
    (stroke (width 0) (type default))
  )
  (wire (pts (xy 373.38 144.78) (xy 373.38 147.32))
    (stroke (width 0) (type default))
  )
  (wire (pts (xy 139.7 86.36) (xy 146.05 86.36))
    (stroke (width 0) (type default))
  )
  (wire (pts (xy 298.45 144.78) (xy 302.26 144.78))
    (stroke (width 0) (type default))
  )
  (wire (pts (xy 340.36 58.42) (xy 340.36 60.96))
    (stroke (width 0) (type default))
  )
  (wire (pts (xy 39.37 200.66) (xy 39.37 199.39))
    (stroke (width 0) (type default))
  )
  (wire (pts (xy 299.72 157.48) (xy 302.26 157.48))
    (stroke (width 0) (type default))
  )
  (wire (pts (xy 367.03 147.32) (xy 373.38 147.32))
    (stroke (width 0) (type default))
  )
  (wire (pts (xy 116.84 217.17) (xy 123.19 217.17))
    (stroke (width 0) (type default))
  )
  (wire (pts (xy 335.28 45.72) (xy 335.28 48.26))
    (stroke (width 0) (type default))
  )
  (wire (pts (xy 107.95 237.49) (xy 111.76 237.49))
    (stroke (width 0) (type default))
  )
  (wire (pts (xy 137.16 231.14) (xy 137.16 233.68))
    (stroke (width 0) (type default))
  )

  (text "DisplayPorts" (at 67.31 140.97 0)
    (effects (font (size 2.54 2.54) (thickness 0.508) bold) (justify left bottom))
  )
  (text "Thunderbolt Controller Misc\n" (at 303.53 133.35 0)
    (effects (font (size 2.54 2.54) (thickness 0.508) bold) (justify left bottom))
  )
  (text "PCIe Clock Generator" (at 333.375 33.655 0)
    (effects (font (size 2.54 2.54) (thickness 0.508) bold) (justify left bottom))
  )
  (text "SPI Flash Memory" (at 251.46 208.28 0)
    (effects (font (size 2.54 2.54) (thickness 0.508) bold) (justify left bottom))
  )
  (text "Thunderbolt Controller \n" (at 83.185 28.575 0)
    (effects (font (size 2.54 2.54) (thickness 0.508) bold) (justify left bottom))
  )
  (text "Thunderbolt Controller Debug\n\n" (at 180.34 137.795 0)
    (effects (font (size 2.54 2.54) (thickness 0.508) bold) (justify left bottom))
  )
  (text "Support 150-mils and 200-mils package" (at 247.65 250.825 0)
    (effects (font (size 1.27 1.27)) (justify left bottom))
  )
  (text "PCIe x4 Gen3" (at 196.215 33.02 0)
    (effects (font (size 2.54 2.54) (thickness 0.508) bold) (justify left bottom))
  )

  (label "FLASH_HOLD" (at 224.79 237.49 0) (fields_autoplaced)
    (effects (font (size 1.27 1.27)) (justify left bottom))
  )
  (label "PCIE_CLK_JHL_P" (at 382.27 55.88 180) (fields_autoplaced)
    (effects (font (size 1.27 1.27)) (justify right bottom))
  )
  (label "TX2_P" (at 238.76 62.23 0) (fields_autoplaced)
    (effects (font (size 1.27 1.27)) (justify left bottom))
  )
  (label "PA_TX0_N" (at 64.77 58.42 0) (fields_autoplaced)
    (effects (font (size 1.27 1.27)) (justify left bottom))
  )
  (label "TX2_N" (at 238.76 64.77 0) (fields_autoplaced)
    (effects (font (size 1.27 1.27)) (justify left bottom))
  )
  (label "PA_TX1_N" (at 64.77 66.04 0) (fields_autoplaced)
    (effects (font (size 1.27 1.27)) (justify left bottom))
  )
  (label "FLASH_WP" (at 116.84 209.55 180) (fields_autoplaced)
    (effects (font (size 1.27 1.27)) (justify right bottom))
  )
  (label "PCIE_CLK_JHL_P" (at 165.1 77.47 0) (fields_autoplaced)
    (effects (font (size 1.27 1.27)) (justify left bottom))
  )
  (label "PA_AUX_P" (at 64.77 71.12 0) (fields_autoplaced)
    (effects (font (size 1.27 1.27)) (justify left bottom))
  )
  (label "TX3_P" (at 238.76 69.85 0) (fields_autoplaced)
    (effects (font (size 1.27 1.27)) (justify left bottom))
  )
  (label "TX1_N" (at 238.76 57.15 0) (fields_autoplaced)
    (effects (font (size 1.27 1.27)) (justify left bottom))
  )
  (label "FLASH_WP" (at 295.91 234.95 0) (fields_autoplaced)
    (effects (font (size 1.27 1.27)) (justify left bottom))
  )
  (label "PA_AUX_N" (at 64.77 73.66 0) (fields_autoplaced)
    (effects (font (size 1.27 1.27)) (justify left bottom))
  )
  (label "TX0_P" (at 238.76 46.99 0) (fields_autoplaced)
    (effects (font (size 1.27 1.27)) (justify left bottom))
  )
  (label "TX0_N" (at 238.76 49.53 0) (fields_autoplaced)
    (effects (font (size 1.27 1.27)) (justify left bottom))
  )
  (label "PCIE_CLK_JHL_N" (at 382.27 58.42 180) (fields_autoplaced)
    (effects (font (size 1.27 1.27)) (justify right bottom))
  )
  (label "FLASH_HOLD" (at 295.91 237.49 0) (fields_autoplaced)
    (effects (font (size 1.27 1.27)) (justify left bottom))
  )
  (label "PA_TX0_P" (at 64.77 55.88 0) (fields_autoplaced)
    (effects (font (size 1.27 1.27)) (justify left bottom))
  )
  (label "FLASH_WP" (at 224.79 234.95 0) (fields_autoplaced)
    (effects (font (size 1.27 1.27)) (justify left bottom))
  )
  (label "TX1_P" (at 238.76 54.61 0) (fields_autoplaced)
    (effects (font (size 1.27 1.27)) (justify left bottom))
  )
  (label "PCIE_CLK_JHL_N" (at 165.1 80.01 0) (fields_autoplaced)
    (effects (font (size 1.27 1.27)) (justify left bottom))
  )
  (label "TX3_N" (at 238.76 72.39 0) (fields_autoplaced)
    (effects (font (size 1.27 1.27)) (justify left bottom))
  )
  (label "PA_TX1_P" (at 64.77 63.5 0) (fields_autoplaced)
    (effects (font (size 1.27 1.27)) (justify left bottom))
  )

  (global_label "PCIE_TX3_P" (shape input) (at 278.13 69.85 0) (fields_autoplaced)
    (effects (font (size 1.27 1.27)) (justify left))
    (property "Intersheetrefs" "${INTERSHEET_REFS}" (at 291.4288 69.7706 0)
      (effects (font (size 1.27 1.27)) (justify left) hide)
    )
  )
  (global_label "3V3_SYS" (shape input) (at 287.02 144.78 180) (fields_autoplaced)
    (effects (font (size 1.27 1.27)) (justify right))
    (property "Intersheetrefs" "${INTERSHEET_REFS}" (at 276.624 144.7006 0)
      (effects (font (size 1.27 1.27)) (justify right) hide)
    )
  )
  (global_label "PCIE_TX2_N" (shape input) (at 278.13 64.77 0) (fields_autoplaced)
    (effects (font (size 1.27 1.27)) (justify left))
    (property "Intersheetrefs" "${INTERSHEET_REFS}" (at 291.4893 64.6906 0)
      (effects (font (size 1.27 1.27)) (justify left) hide)
    )
  )
  (global_label "HPD" (shape input) (at 72.39 91.44 180) (fields_autoplaced)
    (effects (font (size 1.27 1.27)) (justify right))
    (property "Intersheetrefs" "${INTERSHEET_REFS}" (at 66.1064 91.3606 0)
      (effects (font (size 1.27 1.27)) (justify right) hide)
    )
  )
  (global_label "SPI_SCLK" (shape input) (at 224.79 240.03 180) (fields_autoplaced)
    (effects (font (size 1.27 1.27)) (justify right))
    (property "Intersheetrefs" "${INTERSHEET_REFS}" (at 213.5474 240.1094 0)
      (effects (font (size 1.27 1.27)) (justify right) hide)
    )
  )
  (global_label "SPI_SCLK" (shape input) (at 326.39 240.03 0) (fields_autoplaced)
    (effects (font (size 1.27 1.27)) (justify left))
    (property "Intersheetrefs" "${INTERSHEET_REFS}" (at 337.6326 239.9506 0)
      (effects (font (size 1.27 1.27)) (justify left) hide)
    )
  )
  (global_label "3V3_SYS" (shape input) (at 231.14 212.09 180) (fields_autoplaced)
    (effects (font (size 1.27 1.27)) (justify right))
    (property "Intersheetrefs" "${INTERSHEET_REFS}" (at 220.744 212.1694 0)
      (effects (font (size 1.27 1.27)) (justify right) hide)
    )
  )
  (global_label "SPI_MISO" (shape input) (at 224.79 232.41 180) (fields_autoplaced)
    (effects (font (size 1.27 1.27)) (justify right))
    (property "Intersheetrefs" "${INTERSHEET_REFS}" (at 213.7288 232.4894 0)
      (effects (font (size 1.27 1.27)) (justify right) hide)
    )
  )
  (global_label "AUX_N" (shape input) (at 33.02 73.66 180) (fields_autoplaced)
    (effects (font (size 1.27 1.27)) (justify right))
    (property "Intersheetrefs" "${INTERSHEET_REFS}" (at 24.6802 73.5806 0)
      (effects (font (size 1.27 1.27)) (justify right) hide)
    )
  )
  (global_label "3V3_SYS" (shape input) (at 331.47 39.37 180) (fields_autoplaced)
    (effects (font (size 1.27 1.27)) (justify right))
    (property "Intersheetrefs" "${INTERSHEET_REFS}" (at 321.074 39.2906 0)
      (effects (font (size 1.27 1.27)) (justify right) hide)
    )
  )
  (global_label "I2C1_IRQ" (shape input) (at 121.92 232.41 0) (fields_autoplaced)
    (effects (font (size 1.27 1.27)) (justify left))
    (property "Intersheetrefs" "${INTERSHEET_REFS}" (at 132.7998 232.3306 0)
      (effects (font (size 1.27 1.27)) (justify left) hide)
    )
  )
  (global_label "SPI_CS" (shape input) (at 359.41 167.64 0) (fields_autoplaced)
    (effects (font (size 1.27 1.27)) (justify left))
    (property "Intersheetrefs" "${INTERSHEET_REFS}" (at 368.3545 167.5606 0)
      (effects (font (size 1.27 1.27)) (justify left) hide)
    )
  )
  (global_label "TB_RX0_P" (shape input) (at 66.04 40.64 180) (fields_autoplaced)
    (effects (font (size 1.27 1.27)) (justify right))
    (property "Intersheetrefs" "${INTERSHEET_REFS}" (at 54.495 40.5606 0)
      (effects (font (size 1.27 1.27)) (justify right) hide)
    )
  )
  (global_label "PCIE_TX0_N" (shape input) (at 278.13 49.53 0) (fields_autoplaced)
    (effects (font (size 1.27 1.27)) (justify left))
    (property "Intersheetrefs" "${INTERSHEET_REFS}" (at 291.4893 49.4506 0)
      (effects (font (size 1.27 1.27)) (justify left) hide)
    )
  )
  (global_label "SPI_MOSI" (shape input) (at 359.41 162.56 0) (fields_autoplaced)
    (effects (font (size 1.27 1.27)) (justify left))
    (property "Intersheetrefs" "${INTERSHEET_REFS}" (at 370.4712 162.4806 0)
      (effects (font (size 1.27 1.27)) (justify left) hide)
    )
  )
  (global_label "PCIE_RX3_N" (shape input) (at 172.72 72.39 180) (fields_autoplaced)
    (effects (font (size 1.27 1.27)) (justify right))
    (property "Intersheetrefs" "${INTERSHEET_REFS}" (at 159.0583 72.3106 0)
      (effects (font (size 1.27 1.27)) (justify right) hide)
    )
  )
  (global_label "PCIE_RX2_N" (shape input) (at 172.72 64.77 180) (fields_autoplaced)
    (effects (font (size 1.27 1.27)) (justify right))
    (property "Intersheetrefs" "${INTERSHEET_REFS}" (at 159.0583 64.6906 0)
      (effects (font (size 1.27 1.27)) (justify right) hide)
    )
  )
  (global_label "PCIE_PWRGD" (shape input) (at 240.03 80.01 0) (fields_autoplaced)
    (effects (font (size 1.27 1.27)) (justify left))
    (property "Intersheetrefs" "${INTERSHEET_REFS}" (at 254.236 79.9306 0)
      (effects (font (size 1.27 1.27)) (justify left) hide)
    )
  )
  (global_label "PCIE_RX0_N" (shape input) (at 172.72 49.53 180) (fields_autoplaced)
    (effects (font (size 1.27 1.27)) (justify right))
    (property "Intersheetrefs" "${INTERSHEET_REFS}" (at 159.0583 49.4506 0)
      (effects (font (size 1.27 1.27)) (justify right) hide)
    )
  )
  (global_label "PCIE_RX2_P" (shape input) (at 172.72 62.23 180) (fields_autoplaced)
    (effects (font (size 1.27 1.27)) (justify right))
    (property "Intersheetrefs" "${INTERSHEET_REFS}" (at 159.1188 62.1506 0)
      (effects (font (size 1.27 1.27)) (justify right) hide)
    )
  )
  (global_label "PCIE_RX0_P" (shape input) (at 172.72 46.99 180) (fields_autoplaced)
    (effects (font (size 1.27 1.27)) (justify right))
    (property "Intersheetrefs" "${INTERSHEET_REFS}" (at 159.1188 46.9106 0)
      (effects (font (size 1.27 1.27)) (justify right) hide)
    )
  )
  (global_label "3V3_SYS" (shape input) (at 121.92 234.95 0) (fields_autoplaced)
    (effects (font (size 1.27 1.27)) (justify left))
    (property "Intersheetrefs" "${INTERSHEET_REFS}" (at 132.316 234.8706 0)
      (effects (font (size 1.27 1.27)) (justify left) hide)
    )
  )
  (global_label "USB_RP_P" (shape input) (at 62.23 78.74 180) (fields_autoplaced)
    (effects (font (size 1.27 1.27)) (justify right))
    (property "Intersheetrefs" "${INTERSHEET_REFS}" (at 50.2617 78.6606 0)
      (effects (font (size 1.27 1.27)) (justify right) hide)
    )
  )
  (global_label "LSX_R2P" (shape input) (at 40.64 86.36 180) (fields_autoplaced)
    (effects (font (size 1.27 1.27)) (justify right))
    (property "Intersheetrefs" "${INTERSHEET_REFS}" (at 30.0626 86.2806 0)
      (effects (font (size 1.27 1.27)) (justify right) hide)
    )
  )
  (global_label "3V3_SYS" (shape input) (at 137.16 231.14 90) (fields_autoplaced)
    (effects (font (size 1.27 1.27)) (justify left))
    (property "Intersheetrefs" "${INTERSHEET_REFS}" (at 137.0806 220.744 90)
      (effects (font (size 1.27 1.27)) (justify left) hide)
    )
  )
  (global_label "3V3_SYS" (shape input) (at 326.39 237.49 0) (fields_autoplaced)
    (effects (font (size 1.27 1.27)) (justify left))
    (property "Intersheetrefs" "${INTERSHEET_REFS}" (at 336.786 237.4106 0)
      (effects (font (size 1.27 1.27)) (justify left) hide)
    )
  )
  (global_label "TB_RX0_N" (shape input) (at 66.04 43.18 180) (fields_autoplaced)
    (effects (font (size 1.27 1.27)) (justify right))
    (property "Intersheetrefs" "${INTERSHEET_REFS}" (at 54.4345 43.1006 0)
      (effects (font (size 1.27 1.27)) (justify right) hide)
    )
  )
  (global_label "TB_TX0_N" (shape input) (at 33.02 58.42 180) (fields_autoplaced)
    (effects (font (size 1.27 1.27)) (justify right))
    (property "Intersheetrefs" "${INTERSHEET_REFS}" (at 21.7169 58.3406 0)
      (effects (font (size 1.27 1.27)) (justify right) hide)
    )
  )
  (global_label "I2C1_SCL" (shape input) (at 116.84 207.01 0) (fields_autoplaced)
    (effects (font (size 1.27 1.27)) (justify left))
    (property "Intersheetrefs" "${INTERSHEET_REFS}" (at 128.0221 206.9306 0)
      (effects (font (size 1.27 1.27)) (justify left) hide)
    )
  )
  (global_label "3V3_SYS" (shape input) (at 170.18 85.09 180) (fields_autoplaced)
    (effects (font (size 1.27 1.27)) (justify right))
    (property "Intersheetrefs" "${INTERSHEET_REFS}" (at 159.784 85.0106 0)
      (effects (font (size 1.27 1.27)) (justify right) hide)
    )
  )
  (global_label "TB_RX1_P" (shape input) (at 66.04 48.26 180) (fields_autoplaced)
    (effects (font (size 1.27 1.27)) (justify right))
    (property "Intersheetrefs" "${INTERSHEET_REFS}" (at 54.495 48.3394 0)
      (effects (font (size 1.27 1.27)) (justify right) hide)
    )
  )
  (global_label "TB_TX1_N" (shape input) (at 33.02 66.04 180) (fields_autoplaced)
    (effects (font (size 1.27 1.27)) (justify right))
    (property "Intersheetrefs" "${INTERSHEET_REFS}" (at 21.7169 66.1194 0)
      (effects (font (size 1.27 1.27)) (justify right) hide)
    )
  )
  (global_label "SPI_MISO" (shape input) (at 359.41 165.1 0) (fields_autoplaced)
    (effects (font (size 1.27 1.27)) (justify left))
    (property "Intersheetrefs" "${INTERSHEET_REFS}" (at 370.4712 165.0206 0)
      (effects (font (size 1.27 1.27)) (justify left) hide)
    )
  )
  (global_label "PCIE_TX2_P" (shape input) (at 278.13 62.23 0) (fields_autoplaced)
    (effects (font (size 1.27 1.27)) (justify left))
    (property "Intersheetrefs" "${INTERSHEET_REFS}" (at 291.4288 62.1506 0)
      (effects (font (size 1.27 1.27)) (justify left) hide)
    )
  )
  (global_label "SPI_CS" (shape input) (at 224.79 242.57 180) (fields_autoplaced)
    (effects (font (size 1.27 1.27)) (justify right))
    (property "Intersheetrefs" "${INTERSHEET_REFS}" (at 215.8455 242.6494 0)
      (effects (font (size 1.27 1.27)) (justify right) hide)
    )
  )
  (global_label "AUX_P" (shape input) (at 33.02 71.12 180) (fields_autoplaced)
    (effects (font (size 1.27 1.27)) (justify right))
    (property "Intersheetrefs" "${INTERSHEET_REFS}" (at 24.7407 71.0406 0)
      (effects (font (size 1.27 1.27)) (justify right) hide)
    )
  )
  (global_label "USB_RP_N" (shape input) (at 62.23 81.28 180) (fields_autoplaced)
    (effects (font (size 1.27 1.27)) (justify right))
    (property "Intersheetrefs" "${INTERSHEET_REFS}" (at 50.2012 81.2006 0)
      (effects (font (size 1.27 1.27)) (justify right) hide)
    )
  )
  (global_label "PCIE_RX1_P" (shape input) (at 172.72 54.61 180) (fields_autoplaced)
    (effects (font (size 1.27 1.27)) (justify right))
    (property "Intersheetrefs" "${INTERSHEET_REFS}" (at 159.1188 54.5306 0)
      (effects (font (size 1.27 1.27)) (justify right) hide)
    )
  )
  (global_label "PCIE_RX3_P" (shape input) (at 172.72 69.85 180) (fields_autoplaced)
    (effects (font (size 1.27 1.27)) (justify right))
    (property "Intersheetrefs" "${INTERSHEET_REFS}" (at 159.1188 69.7706 0)
      (effects (font (size 1.27 1.27)) (justify right) hide)
    )
  )
  (global_label "LSX_P2R" (shape input) (at 40.64 88.9 180) (fields_autoplaced)
    (effects (font (size 1.27 1.27)) (justify right))
    (property "Intersheetrefs" "${INTERSHEET_REFS}" (at 30.0626 88.8206 0)
      (effects (font (size 1.27 1.27)) (justify right) hide)
    )
  )
  (global_label "PCIE_TX3_N" (shape input) (at 278.13 72.39 0) (fields_autoplaced)
    (effects (font (size 1.27 1.27)) (justify left))
    (property "Intersheetrefs" "${INTERSHEET_REFS}" (at 291.4893 72.3106 0)
      (effects (font (size 1.27 1.27)) (justify left) hide)
    )
  )
  (global_label "PCIE_TX1_N" (shape input) (at 278.13 57.15 0) (fields_autoplaced)
    (effects (font (size 1.27 1.27)) (justify left))
    (property "Intersheetrefs" "${INTERSHEET_REFS}" (at 291.4893 57.0706 0)
      (effects (font (size 1.27 1.27)) (justify left) hide)
    )
  )
  (global_label "SPI_MOSI" (shape input) (at 224.79 229.87 180) (fields_autoplaced)
    (effects (font (size 1.27 1.27)) (justify right))
    (property "Intersheetrefs" "${INTERSHEET_REFS}" (at 213.7288 229.9494 0)
      (effects (font (size 1.27 1.27)) (justify right) hide)
    )
  )
  (global_label "3V3_SYS" (shape input) (at 299.72 215.9 90) (fields_autoplaced)
    (effects (font (size 1.27 1.27)) (justify left))
    (property "Intersheetrefs" "${INTERSHEET_REFS}" (at 299.6406 205.504 90)
      (effects (font (size 1.27 1.27)) (justify left) hide)
    )
  )
  (global_label "PCIE_RX1_N" (shape input) (at 172.72 57.15 180) (fields_autoplaced)
    (effects (font (size 1.27 1.27)) (justify right))
    (property "Intersheetrefs" "${INTERSHEET_REFS}" (at 159.0583 57.0706 0)
      (effects (font (size 1.27 1.27)) (justify right) hide)
    )
  )
  (global_label "PCIE_CLK_CON_N" (shape input) (at 382.27 53.34 0) (fields_autoplaced)
    (effects (font (size 1.27 1.27)) (justify left))
    (property "Intersheetrefs" "${INTERSHEET_REFS}" (at 400.7093 53.2606 0)
      (effects (font (size 1.27 1.27)) (justify left) hide)
    )
  )
  (global_label "PCIE_TX1_P" (shape input) (at 278.13 54.61 0) (fields_autoplaced)
    (effects (font (size 1.27 1.27)) (justify left))
    (property "Intersheetrefs" "${INTERSHEET_REFS}" (at 291.4288 54.5306 0)
      (effects (font (size 1.27 1.27)) (justify left) hide)
    )
  )
  (global_label "SPI_SCLK" (shape input) (at 359.41 170.18 0) (fields_autoplaced)
    (effects (font (size 1.27 1.27)) (justify left))
    (property "Intersheetrefs" "${INTERSHEET_REFS}" (at 370.6526 170.1006 0)
      (effects (font (size 1.27 1.27)) (justify left) hide)
    )
  )
  (global_label "TB_TX0_P" (shape input) (at 33.02 55.88 180) (fields_autoplaced)
    (effects (font (size 1.27 1.27)) (justify right))
    (property "Intersheetrefs" "${INTERSHEET_REFS}" (at 21.7774 55.8006 0)
      (effects (font (size 1.27 1.27)) (justify right) hide)
    )
  )
  (global_label "PCIE_CLK_CON_P" (shape input) (at 382.27 50.8 0) (fields_autoplaced)
    (effects (font (size 1.27 1.27)) (justify left))
    (property "Intersheetrefs" "${INTERSHEET_REFS}" (at 400.6488 50.7206 0)
      (effects (font (size 1.27 1.27)) (justify left) hide)
    )
  )
  (global_label "PCIE_WAKE" (shape input) (at 138.43 242.57 0) (fields_autoplaced)
    (effects (font (size 1.27 1.27)) (justify left))
    (property "Intersheetrefs" "${INTERSHEET_REFS}" (at 151.0636 242.6494 0)
      (effects (font (size 1.27 1.27)) (justify left) hide)
    )
  )
  (global_label "TB_RX1_N" (shape input) (at 66.04 50.8 180) (fields_autoplaced)
    (effects (font (size 1.27 1.27)) (justify right))
    (property "Intersheetrefs" "${INTERSHEET_REFS}" (at 54.4345 50.8794 0)
      (effects (font (size 1.27 1.27)) (justify right) hide)
    )
  )
  (global_label "SPI_MOSI" (shape input) (at 326.39 229.87 0) (fields_autoplaced)
    (effects (font (size 1.27 1.27)) (justify left))
    (property "Intersheetrefs" "${INTERSHEET_REFS}" (at 337.4512 229.7906 0)
      (effects (font (size 1.27 1.27)) (justify left) hide)
    )
  )
  (global_label "TB_TX1_P" (shape input) (at 33.02 63.5 180) (fields_autoplaced)
    (effects (font (size 1.27 1.27)) (justify right))
    (property "Intersheetrefs" "${INTERSHEET_REFS}" (at 21.7774 63.5794 0)
      (effects (font (size 1.27 1.27)) (justify right) hide)
    )
  )
  (global_label "I2C1_SDA" (shape input) (at 116.84 204.47 0) (fields_autoplaced)
    (effects (font (size 1.27 1.27)) (justify left))
    (property "Intersheetrefs" "${INTERSHEET_REFS}" (at 128.0826 204.3906 0)
      (effects (font (size 1.27 1.27)) (justify left) hide)
    )
  )
  (global_label "PCIE_TX0_P" (shape input) (at 278.13 46.99 0) (fields_autoplaced)
    (effects (font (size 1.27 1.27)) (justify left))
    (property "Intersheetrefs" "${INTERSHEET_REFS}" (at 291.4288 46.9106 0)
      (effects (font (size 1.27 1.27)) (justify left) hide)
    )
  )
  (global_label "SPI_CS" (shape input) (at 326.39 242.57 0) (fields_autoplaced)
    (effects (font (size 1.27 1.27)) (justify left))
    (property "Intersheetrefs" "${INTERSHEET_REFS}" (at 335.3345 242.4906 0)
      (effects (font (size 1.27 1.27)) (justify left) hide)
    )
  )
  (global_label "SPI_MISO" (shape input) (at 326.39 232.41 0) (fields_autoplaced)
    (effects (font (size 1.27 1.27)) (justify left))
    (property "Intersheetrefs" "${INTERSHEET_REFS}" (at 337.4512 232.3306 0)
      (effects (font (size 1.27 1.27)) (justify left) hide)
    )
  )
  (global_label "RESET_N" (shape input) (at 359.41 149.86 0) (fields_autoplaced)
    (effects (font (size 1.27 1.27)) (justify left))
    (property "Intersheetrefs" "${INTERSHEET_REFS}" (at 369.8664 149.7806 0)
      (effects (font (size 1.27 1.27)) (justify left) hide)
    )
  )
  (global_label "3V3_SYS" (shape input) (at 266.7 228.6 90) (fields_autoplaced)
    (effects (font (size 1.27 1.27)) (justify left))
    (property "Intersheetrefs" "${INTERSHEET_REFS}" (at 266.6206 218.204 90)
      (effects (font (size 1.27 1.27)) (justify left) hide)
    )
  )

  (symbol (lib_id "antmicropower:GND") (at 394.97 156.21 90) (unit 1)
    (in_bom yes) (on_board yes) (dnp no)
    (property "Reference" "#PWR0149" (at 401.32 156.21 0)
      (effects (font (size 1.27 1.27)) hide)
    )
    (property "Value" "GND" (at 399.415 158.115 0)
      (effects (font (size 1.27 1.27) (thickness 0.15)) (justify left bottom))
    )
    (property "Footprint" "" (at 394.97 156.21 0)
      (effects (font (size 1.27 1.27) (thickness 0.15)) (justify left bottom) hide)
    )
    (property "Datasheet" "" (at 394.97 156.21 0)
      (effects (font (size 1.27 1.27) (thickness 0.15)) (justify left bottom) hide)
    )
    (property "Author" "Antmicro" (at 402.59 147.32 0)
      (effects (font (size 1.27 1.27) (thickness 0.15)) (justify left bottom) hide)
    )
    (property "License" "Apache-2.0" (at 405.13 147.32 0)
      (effects (font (size 1.27 1.27) (thickness 0.15)) (justify left bottom) hide)
    )
    (pin "1")
    (instances
      (project "thunderbolt-pcie-adapter"
        (path ""
          (reference "#PWR0149") (unit 1)
        )
      )
    )
  )

  (symbol (lib_id "antmicroCapacitors0402:C_10p_0402") (at 309.88 49.53 0) (unit 1)
    (in_bom yes) (on_board yes) (dnp no)
    (property "Reference" "C113" (at 312.42 46.99 0)
      (effects (font (size 1.27 1.27) (thickness 0.15)))
    )
    (property "Value" "C_10p_0402" (at 330.2 59.69 0)
      (effects (font (size 1.27 1.27) (thickness 0.15)) (justify left bottom) hide)
    )
    (property "Footprint" "antmicro-footprints:C_0402_1005Metric" (at 330.2 62.23 0)
      (effects (font (size 1.27 1.27) (thickness 0.15)) (justify left bottom) hide)
    )
    (property "Datasheet" "https://www.murata.com/products/productdetail?partno=GCM1555C1H100GA16%23" (at 330.2 64.77 0)
      (effects (font (size 1.27 1.27) (thickness 0.15)) (justify left bottom) hide)
    )
    (property "MPN" "GCM1555C1H100GA16D" (at 330.2 67.31 0)
      (effects (font (size 1.27 1.27) (thickness 0.15)) (justify left bottom) hide)
    )
    (property "Manufacturer" "Murata" (at 330.2 69.85 0)
      (effects (font (size 1.27 1.27) (thickness 0.15)) (justify left bottom) hide)
    )
    (property "License" "Apache-2.0" (at 330.2 72.39 0)
      (effects (font (size 1.27 1.27) (thickness 0.15)) (justify left bottom) hide)
    )
    (property "Val" "10p" (at 310.515 53.34 0)
      (effects (font (size 1.27 1.27) (thickness 0.15)) (justify left bottom))
    )
    (property "Voltage" "50V" (at 330.2 77.47 0)
      (effects (font (size 1.27 1.27)) (justify left bottom) hide)
    )
    (property "Dielectric" "C0G" (at 330.2 80.01 0)
      (effects (font (size 1.27 1.27)) (justify left bottom) hide)
    )
    (property "Author" "Antmicro" (at 330.2 74.93 0)
      (effects (font (size 1.27 1.27) (thickness 0.15)) (justify left bottom) hide)
    )
    (pin "1")
    (pin "2")
    (instances
      (project "thunderbolt-pcie-adapter"
        (path ""
          (reference "C113") (unit 1)
        )
      )
    )
  )

  (symbol (lib_id "antmicroCapacitors0402:C_100n_0402") (at 44.45 71.12 0) (unit 1)
    (in_bom yes) (on_board yes) (dnp no)
    (property "Reference" "C101" (at 43.815 69.85 0)
      (effects (font (size 1.27 1.27) (thickness 0.15)))
    )
    (property "Value" "C_100n_0402" (at 64.77 81.28 0)
      (effects (font (size 1.27 1.27) (thickness 0.15)) (justify left bottom) hide)
    )
    (property "Footprint" "antmicro-footprints:C_0402_1005Metric" (at 64.77 83.82 0)
      (effects (font (size 1.27 1.27) (thickness 0.15)) (justify left bottom) hide)
    )
    (property "Datasheet" "https://www.murata.com/products/productdetail?partno=GRM155R61H104KE14%23" (at 64.77 86.36 0)
      (effects (font (size 1.27 1.27) (thickness 0.15)) (justify left bottom) hide)
    )
    (property "MPN" "GRM155R61H104KE14D" (at 64.77 88.9 0)
      (effects (font (size 1.27 1.27) (thickness 0.15)) (justify left bottom) hide)
    )
    (property "Manufacturer" "Murata" (at 64.77 91.44 0)
      (effects (font (size 1.27 1.27) (thickness 0.15)) (justify left bottom) hide)
    )
    (property "License" "Apache-2.0" (at 64.77 93.98 0)
      (effects (font (size 1.27 1.27) (thickness 0.15)) (justify left bottom) hide)
    )
    (property "Val" "100n" (at 48.26 70.485 0)
      (effects (font (size 1.27 1.27) (thickness 0.15)) (justify left bottom))
    )
    (property "Voltage" "50V" (at 64.77 99.06 0)
      (effects (font (size 1.27 1.27)) (justify left bottom) hide)
    )
    (property "Dielectric" "X5R" (at 64.77 101.6 0)
      (effects (font (size 1.27 1.27)) (justify left bottom) hide)
    )
    (property "Author" "Antmicro" (at 64.77 96.52 0)
      (effects (font (size 1.27 1.27) (thickness 0.15)) (justify left bottom) hide)
    )
    (pin "1")
    (pin "2")
    (instances
      (project "thunderbolt-pcie-adapter"
        (path ""
          (reference "C101") (unit 1)
        )
      )
    )
  )

  (symbol (lib_id "antmicroResistors0402:R_1M_0402") (at 52.07 97.79 90) (unit 1)
    (in_bom yes) (on_board yes) (dnp no)
    (property "Reference" "R54" (at 48.895 94.615 90)
      (effects (font (size 1.27 1.27) (thickness 0.15)))
    )
    (property "Value" "R_1M_0402" (at 64.77 77.47 0)
      (effects (font (size 1.27 1.27) (thickness 0.15)) (justify left bottom) hide)
    )
    (property "Footprint" "antmicro-footprints:R_0402_1005Metric" (at 67.31 77.47 0)
      (effects (font (size 1.27 1.27) (thickness 0.15)) (justify left bottom) hide)
    )
    (property "Datasheet" "https://www.bourns.com/docs/product-datasheets/cr.pdf" (at 69.85 77.47 0)
      (effects (font (size 1.27 1.27) (thickness 0.15)) (justify left bottom) hide)
    )
    (property "MPN" "CR0402-FX-1004GLF" (at 72.39 77.47 0)
      (effects (font (size 1.27 1.27) (thickness 0.15)) (justify left bottom) hide)
    )
    (property "Manufacturer" "Bourns" (at 74.93 77.47 0)
      (effects (font (size 1.27 1.27) (thickness 0.15)) (justify left bottom) hide)
    )
    (property "License" "Apache-2.0" (at 77.47 77.47 0)
      (effects (font (size 1.27 1.27) (thickness 0.15)) (justify left bottom) hide)
    )
    (property "Val" "1M" (at 50.165 95.885 90)
      (effects (font (size 1.27 1.27) (thickness 0.15)) (justify left bottom))
    )
    (property "Tolerance" "1%" (at 62.23 77.47 0)
      (effects (font (size 1.27 1.27)) (justify left bottom) hide)
    )
    (property "Author" "Antmicro" (at 80.01 77.47 0)
      (effects (font (size 1.27 1.27) (thickness 0.15)) (justify left bottom) hide)
    )
    (pin "1")
    (pin "2")
    (instances
      (project "thunderbolt-pcie-adapter"
        (path ""
          (reference "R54") (unit 1)
        )
      )
    )
  )

  (symbol (lib_id "antmicropower:GND") (at 398.78 162.56 90) (unit 1)
    (in_bom yes) (on_board yes) (dnp no)
    (property "Reference" "#PWR0151" (at 405.13 162.56 0)
      (effects (font (size 1.27 1.27)) hide)
    )
    (property "Value" "GND" (at 403.225 164.465 0)
      (effects (font (size 1.27 1.27) (thickness 0.15)) (justify left bottom))
    )
    (property "Footprint" "" (at 398.78 162.56 0)
      (effects (font (size 1.27 1.27) (thickness 0.15)) (justify left bottom) hide)
    )
    (property "Datasheet" "" (at 398.78 162.56 0)
      (effects (font (size 1.27 1.27) (thickness 0.15)) (justify left bottom) hide)
    )
    (property "Author" "Antmicro" (at 406.4 153.67 0)
      (effects (font (size 1.27 1.27) (thickness 0.15)) (justify left bottom) hide)
    )
    (property "License" "Apache-2.0" (at 408.94 153.67 0)
      (effects (font (size 1.27 1.27) (thickness 0.15)) (justify left bottom) hide)
    )
    (pin "1")
    (instances
      (project "thunderbolt-pcie-adapter"
        (path ""
          (reference "#PWR0151") (unit 1)
        )
      )
    )
  )

  (symbol (lib_id "antmicroCapacitors0402:C_220n_0402") (at 259.08 57.15 0) (unit 1)
    (in_bom yes) (on_board yes) (dnp no)
    (property "Reference" "C106" (at 252.095 55.88 0)
      (effects (font (size 1.27 1.27) (thickness 0.15)))
    )
    (property "Value" "C_220n_0402" (at 279.4 67.31 0)
      (effects (font (size 1.27 1.27) (thickness 0.15)) (justify left bottom) hide)
    )
    (property "Footprint" "antmicro-footprints:C_0402_1005Metric" (at 279.4 69.85 0)
      (effects (font (size 1.27 1.27) (thickness 0.15)) (justify left bottom) hide)
    )
    (property "Datasheet" "https://www.yageo.com/en/Chart/Download/pdf/CC0402KRX5R6BB224" (at 279.4 72.39 0)
      (effects (font (size 1.27 1.27) (thickness 0.15)) (justify left bottom) hide)
    )
    (property "MPN" "CC0402KRX5R6BB224" (at 279.4 74.93 0)
      (effects (font (size 1.27 1.27) (thickness 0.15)) (justify left bottom) hide)
    )
    (property "Manufacturer" "YAGEO" (at 279.4 77.47 0)
      (effects (font (size 1.27 1.27) (thickness 0.15)) (justify left bottom) hide)
    )
    (property "License" "Apache-2.0" (at 279.4 80.01 0)
      (effects (font (size 1.27 1.27) (thickness 0.15)) (justify left bottom) hide)
    )
    (property "Val" "220n" (at 255.27 56.515 0)
      (effects (font (size 1.27 1.27) (thickness 0.15)) (justify left bottom))
    )
    (property "Voltage" "" (at 279.4 85.09 0)
      (effects (font (size 1.27 1.27)) (justify left bottom) hide)
    )
    (property "Dielectric" "" (at 279.4 87.63 0)
      (effects (font (size 1.27 1.27)) (justify left bottom) hide)
    )
    (property "Author" "Antmicro" (at 279.4 82.55 0)
      (effects (font (size 1.27 1.27) (thickness 0.15)) (justify left bottom) hide)
    )
    (pin "1")
    (pin "2")
    (instances
      (project "thunderbolt-pcie-adapter"
        (path ""
          (reference "C106") (unit 1)
        )
      )
    )
  )

  (symbol (lib_id "antmicropower:GND") (at 123.19 248.92 0) (unit 1)
    (in_bom yes) (on_board yes) (dnp no)
    (property "Reference" "#PWR0166" (at 123.19 255.27 0)
      (effects (font (size 1.27 1.27)) hide)
    )
    (property "Value" "GND" (at 121.285 253.365 0)
      (effects (font (size 1.27 1.27) (thickness 0.15)) (justify left bottom))
    )
    (property "Footprint" "" (at 123.19 248.92 0)
      (effects (font (size 1.27 1.27) (thickness 0.15)) (justify left bottom) hide)
    )
    (property "Datasheet" "" (at 123.19 248.92 0)
      (effects (font (size 1.27 1.27) (thickness 0.15)) (justify left bottom) hide)
    )
    (property "Author" "Antmicro" (at 132.08 256.54 0)
      (effects (font (size 1.27 1.27) (thickness 0.15)) (justify left bottom) hide)
    )
    (property "License" "Apache-2.0" (at 132.08 259.08 0)
      (effects (font (size 1.27 1.27) (thickness 0.15)) (justify left bottom) hide)
    )
    (pin "1")
    (instances
      (project "thunderbolt-pcie-adapter"
        (path ""
          (reference "#PWR0166") (unit 1)
        )
      )
    )
  )

  (symbol (lib_id "antmicroResistors0402:R_3k01_0402") (at 241.3 85.09 0) (unit 1)
    (in_bom yes) (on_board yes) (dnp no)
    (property "Reference" "R74" (at 243.84 83.185 0)
      (effects (font (size 1.27 1.27) (thickness 0.15)))
    )
    (property "Value" "R_3k01_0402" (at 261.62 97.79 0)
      (effects (font (size 1.27 1.27) (thickness 0.15)) (justify left bottom) hide)
    )
    (property "Footprint" "antmicro-footprints:R_0402_1005Metric" (at 261.62 100.33 0)
      (effects (font (size 1.27 1.27) (thickness 0.15)) (justify left bottom) hide)
    )
    (property "Datasheet" "https://www.bourns.com/docs/product-datasheets/cr.pdf" (at 261.62 102.87 0)
      (effects (font (size 1.27 1.27) (thickness 0.15)) (justify left bottom) hide)
    )
    (property "MPN" "CR0402-FX-3011GLF" (at 261.62 105.41 0)
      (effects (font (size 1.27 1.27) (thickness 0.15)) (justify left bottom) hide)
    )
    (property "Manufacturer" "Bourns" (at 261.62 107.95 0)
      (effects (font (size 1.27 1.27) (thickness 0.15)) (justify left bottom) hide)
    )
    (property "License" "Apache-2.0" (at 261.62 110.49 0)
      (effects (font (size 1.27 1.27) (thickness 0.15)) (justify left bottom) hide)
    )
    (property "Val" "3k01" (at 243.84 86.995 0)
      (effects (font (size 1.27 1.27) (thickness 0.15)))
    )
    (property "Tolerance" "1%" (at 261.62 95.25 0)
      (effects (font (size 1.27 1.27)) (justify left bottom) hide)
    )
    (property "Author" "Antmicro" (at 261.62 113.03 0)
      (effects (font (size 1.27 1.27) (thickness 0.15)) (justify left bottom) hide)
    )
    (pin "1")
    (pin "2")
    (instances
      (project "thunderbolt-pcie-adapter"
        (path ""
          (reference "R74") (unit 1)
        )
      )
    )
  )

  (symbol (lib_id "antmicroInterfaceControllers:JHL6340SLLSQ") (at 76.2 40.64 0) (unit 5)
    (in_bom yes) (on_board yes) (dnp no) (fields_autoplaced)
    (property "Reference" "U4" (at 104.14 31.75 0)
      (effects (font (size 1.27 1.27) (thickness 0.15)))
    )
    (property "Value" "JHL6340SLLSQ" (at 147.32 43.18 0)
      (effects (font (size 1.27 1.27) (thickness 0.15)) (justify left bottom) hide)
    )
    (property "Footprint" "antmicro-footprints:JHL6340SLLSQ" (at 147.32 45.72 0)
      (effects (font (size 1.27 1.27) (thickness 0.15)) (justify left bottom) hide)
    )
    (property "Datasheet" "https://www.thunderbolttechnology.net/sites/default/files/18-241_ThunderboltController_Brief_HI.pdf" (at 147.32 48.26 0)
      (effects (font (size 1.27 1.27) (thickness 0.15)) (justify left bottom) hide)
    )
    (property "Manufacturer" "Intel" (at 147.32 50.8 0)
      (effects (font (size 1.27 1.27) (thickness 0.15)) (justify left bottom) hide)
    )
    (property "MPN" "JHL6340SLLSQ" (at 104.14 34.29 0)
      (effects (font (size 1.27 1.27) (thickness 0.15)))
    )
    (property "Author" "Antmicro" (at 147.32 55.88 0)
      (effects (font (size 1.27 1.27) (thickness 0.15)) (justify left bottom) hide)
    )
    (property "License" "Apache-2.0" (at 147.32 58.42 0)
      (effects (font (size 1.27 1.27) (thickness 0.15)) (justify left bottom) hide)
    )
    (pin "A1")
    (pin "A10")
    (pin "A12")
    (pin "A14")
    (pin "A16")
    (pin "A18")
    (pin "A2")
    (pin "A20")
    (pin "A22")
    (pin "A3")
    (pin "A6")
    (pin "A8")
    (pin "AA22")
    (pin "AA23")
    (pin "AB1")
    (pin "AB10")
    (pin "AB12")
    (pin "AB14")
    (pin "AB16")
    (pin "AB18")
    (pin "AB20")
    (pin "AB22")
    (pin "AB6")
    (pin "AB8")
    (pin "AC10")
    (pin "AC12")
    (pin "AC14")
    (pin "AC16")
    (pin "AC18")
    (pin "AC2")
    (pin "AC20")
    (pin "AC22")
    (pin "AC6")
    (pin "AC8")
    (pin "B1")
    (pin "B10")
    (pin "B12")
    (pin "B14")
    (pin "B16")
    (pin "B18")
    (pin "B2")
    (pin "B20")
    (pin "B22")
    (pin "B3")
    (pin "B6")
    (pin "B8")
    (pin "C1")
    (pin "C2")
    (pin "D1")
    (pin "D11")
    (pin "D12")
    (pin "D13")
    (pin "D15")
    (pin "D16")
    (pin "D18")
    (pin "D5")
    (pin "D8")
    (pin "D9")
    (pin "E11")
    (pin "E12")
    (pin "E13")
    (pin "E15")
    (pin "E16")
    (pin "E22")
    (pin "E23")
    (pin "E4")
    (pin "E5")
    (pin "E6")
    (pin "E8")
    (pin "E9")
    (pin "F11")
    (pin "F12")
    (pin "F13")
    (pin "F15")
    (pin "F16")
    (pin "F18")
    (pin "F20")
    (pin "F5")
    (pin "F6")
    (pin "F8")
    (pin "F9")
    (pin "G22")
    (pin "G23")
    (pin "H1")
    (pin "H11")
    (pin "H12")
    (pin "H13")
    (pin "H15")
    (pin "H16")
    (pin "H18")
    (pin "H2")
    (pin "H20")
    (pin "H5")
    (pin "H8")
    (pin "H9")
    (pin "J11")
    (pin "J12")
    (pin "J13")
    (pin "J15")
    (pin "J16")
    (pin "J18")
    (pin "J19")
    (pin "J20")
    (pin "J22")
    (pin "J23")
    (pin "J5")
    (pin "J8")
    (pin "J9")
    (pin "K1")
    (pin "K2")
    (pin "L11")
    (pin "L12")
    (pin "L13")
    (pin "L16")
    (pin "L18")
    (pin "L19")
    (pin "L20")
    (pin "L22")
    (pin "L23")
    (pin "L5")
    (pin "L6")
    (pin "L8")
    (pin "L9")
    (pin "M1")
    (pin "M11")
    (pin "M12")
    (pin "M13")
    (pin "M15")
    (pin "M16")
    (pin "M18")
    (pin "M19")
    (pin "M2")
    (pin "M20")
    (pin "M5")
    (pin "M6")
    (pin "M8")
    (pin "M9")
    (pin "N11")
    (pin "N12")
    (pin "N13")
    (pin "N18")
    (pin "N19")
    (pin "N20")
    (pin "N22")
    (pin "N23")
    (pin "N5")
    (pin "N8")
    (pin "N9")
    (pin "P1")
    (pin "P2")
    (pin "R11")
    (pin "R12")
    (pin "R13")
    (pin "R15")
    (pin "R16")
    (pin "R18")
    (pin "R19")
    (pin "R20")
    (pin "R22")
    (pin "R23")
    (pin "R5")
    (pin "R6")
    (pin "R8")
    (pin "R9")
    (pin "T1")
    (pin "T11")
    (pin "T12")
    (pin "T13")
    (pin "T15")
    (pin "T16")
    (pin "T18")
    (pin "T2")
    (pin "T20")
    (pin "T5")
    (pin "T6")
    (pin "T8")
    (pin "T9")
    (pin "U22")
    (pin "U23")
    (pin "V11")
    (pin "V12")
    (pin "V13")
    (pin "V15")
    (pin "V16")
    (pin "V20")
    (pin "V5")
    (pin "V6")
    (pin "V8")
    (pin "V9")
    (pin "W20")
    (pin "W22")
    (pin "W23")
    (pin "W5")
    (pin "W6")
    (pin "W8")
    (pin "W9")
    (pin "Y13")
    (pin "Y20")
    (pin "Y9")
    (pin "AC5")
    (pin "F22")
    (pin "F23")
    (pin "H22")
    (pin "H23")
    (pin "K22")
    (pin "K23")
    (pin "L4")
    (pin "M22")
    (pin "M23")
    (pin "N16")
    (pin "P22")
    (pin "P23")
    (pin "T19")
    (pin "T22")
    (pin "T23")
    (pin "V19")
    (pin "V22")
    (pin "V23")
    (pin "Y22")
    (pin "Y23")
    (pin "AA1")
    (pin "AA2")
    (pin "AB11")
    (pin "AB13")
    (pin "AB15")
    (pin "AB17")
    (pin "AB19")
    (pin "AB21")
    (pin "AB7")
    (pin "AB9")
    (pin "AC11")
    (pin "AC13")
    (pin "AC15")
    (pin "AC17")
    (pin "AC19")
    (pin "AC21")
    (pin "AC7")
    (pin "AC9")
    (pin "D2")
    (pin "D4")
    (pin "E2")
    (pin "F1")
    (pin "F2")
    (pin "G1")
    (pin "H4")
    (pin "J1")
    (pin "J2")
    (pin "J4")
    (pin "L1")
    (pin "L2")
    (pin "N1")
    (pin "N2")
    (pin "N4")
    (pin "N6")
    (pin "R1")
    (pin "R2")
    (pin "R4")
    (pin "U1")
    (pin "U2")
    (pin "V1")
    (pin "V2")
    (pin "W1")
    (pin "W11")
    (pin "W12")
    (pin "W19")
    (pin "W2")
    (pin "Y1")
    (pin "Y11")
    (pin "Y12")
    (pin "Y18")
    (pin "Y19")
    (pin "Y2")
    (pin "Y5")
    (pin "Y6")
    (pin "Y8")
    (pin "AB3")
    (pin "AB4")
    (pin "AB5")
    (pin "AC3")
    (pin "AC4")
    (pin "D22")
    (pin "D23")
    (pin "E1")
    (pin "F4")
    (pin "H6")
    (pin "J6")
    (pin "T4")
    (pin "V4")
    (pin "W4")
    (pin "Y4")
    (pin "A11")
    (pin "A13")
    (pin "A15")
    (pin "A17")
    (pin "A19")
    (pin "A21")
    (pin "A4")
    (pin "A5")
    (pin "A7")
    (pin "A9")
    (pin "B11")
    (pin "B13")
    (pin "B15")
    (pin "B17")
    (pin "B19")
    (pin "B21")
    (pin "B4")
    (pin "B5")
    (pin "B7")
    (pin "B9")
    (pin "D19")
    (pin "D20")
    (pin "E19")
    (pin "E20")
    (pin "F19")
    (pin "G2")
    (pin "H19")
    (pin "M4")
    (pin "W15")
    (pin "W16")
    (pin "Y15")
    (pin "Y16")
    (pin "A23")
    (pin "AB2")
    (pin "AB23")
    (pin "AC1")
    (pin "AC23")
    (pin "B23")
    (pin "C22")
    (pin "C23")
    (pin "D6")
    (pin "E18")
    (pin "L15")
    (pin "N15")
    (pin "V18")
    (pin "W13")
    (pin "W18")
    (instances
      (project "thunderbolt-pcie-adapter"
        (path ""
          (reference "U4") (unit 5)
        )
      )
    )
  )

  (symbol (lib_id "antmicroResistors0402:R_100k_0402") (at 137.16 238.76 90) (unit 1)
    (in_bom yes) (on_board yes) (dnp no)
    (property "Reference" "R90" (at 140.335 234.95 90)
      (effects (font (size 1.27 1.27) (thickness 0.15)))
    )
    (property "Value" "R_100k_0402" (at 149.86 218.44 0)
      (effects (font (size 1.27 1.27) (thickness 0.15)) (justify left bottom) hide)
    )
    (property "Footprint" "antmicro-footprints:R_0402_1005Metric" (at 152.4 218.44 0)
      (effects (font (size 1.27 1.27) (thickness 0.15)) (justify left bottom) hide)
    )
    (property "Datasheet" "https://www.bourns.com/docs/product-datasheets/cr.pdf" (at 154.94 218.44 0)
      (effects (font (size 1.27 1.27) (thickness 0.15)) (justify left bottom) hide)
    )
    (property "MPN" "CR0402-FX-1003GLF" (at 157.48 218.44 0)
      (effects (font (size 1.27 1.27) (thickness 0.15)) (justify left bottom) hide)
    )
    (property "Manufacturer" "Bourns" (at 160.02 218.44 0)
      (effects (font (size 1.27 1.27) (thickness 0.15)) (justify left bottom) hide)
    )
    (property "License" "Apache-2.0" (at 162.56 218.44 0)
      (effects (font (size 1.27 1.27) (thickness 0.15)) (justify left bottom) hide)
    )
    (property "Val" "100k" (at 143.51 236.855 90)
      (effects (font (size 1.27 1.27) (thickness 0.15)) (justify left bottom))
    )
    (property "Tolerance" "1%" (at 147.32 218.44 0)
      (effects (font (size 1.27 1.27)) (justify left bottom) hide)
    )
    (property "Author" "Antmicro" (at 165.1 218.44 0)
      (effects (font (size 1.27 1.27) (thickness 0.15)) (justify left bottom) hide)
    )
    (pin "1")
    (pin "2")
    (instances
      (project "thunderbolt-pcie-adapter"
        (path ""
          (reference "R90") (unit 1)
        )
      )
    )
  )

  (symbol (lib_id "antmicroCapacitors0402:C_220n_0402") (at 265.43 69.85 0) (unit 1)
    (in_bom yes) (on_board yes) (dnp no)
    (property "Reference" "C112" (at 264.795 68.58 0)
      (effects (font (size 1.27 1.27) (thickness 0.15)))
    )
    (property "Value" "C_220n_0402" (at 285.75 80.01 0)
      (effects (font (size 1.27 1.27) (thickness 0.15)) (justify left bottom) hide)
    )
    (property "Footprint" "antmicro-footprints:C_0402_1005Metric" (at 285.75 82.55 0)
      (effects (font (size 1.27 1.27) (thickness 0.15)) (justify left bottom) hide)
    )
    (property "Datasheet" "https://www.yageo.com/en/Chart/Download/pdf/CC0402KRX5R6BB224" (at 285.75 85.09 0)
      (effects (font (size 1.27 1.27) (thickness 0.15)) (justify left bottom) hide)
    )
    (property "MPN" "CC0402KRX5R6BB224" (at 285.75 87.63 0)
      (effects (font (size 1.27 1.27) (thickness 0.15)) (justify left bottom) hide)
    )
    (property "Manufacturer" "YAGEO" (at 285.75 90.17 0)
      (effects (font (size 1.27 1.27) (thickness 0.15)) (justify left bottom) hide)
    )
    (property "License" "Apache-2.0" (at 285.75 92.71 0)
      (effects (font (size 1.27 1.27) (thickness 0.15)) (justify left bottom) hide)
    )
    (property "Val" "220n" (at 269.24 69.215 0)
      (effects (font (size 1.27 1.27) (thickness 0.15)) (justify left bottom))
    )
    (property "Voltage" "" (at 285.75 97.79 0)
      (effects (font (size 1.27 1.27)) (justify left bottom) hide)
    )
    (property "Dielectric" "" (at 285.75 100.33 0)
      (effects (font (size 1.27 1.27)) (justify left bottom) hide)
    )
    (property "Author" "Antmicro" (at 285.75 95.25 0)
      (effects (font (size 1.27 1.27) (thickness 0.15)) (justify left bottom) hide)
    )
    (pin "1")
    (pin "2")
    (instances
      (project "thunderbolt-pcie-adapter"
        (path ""
          (reference "C112") (unit 1)
        )
      )
    )
  )

  (symbol (lib_id "antmicroResistors0402:R_2k2_0402") (at 43.18 196.85 0) (unit 1)
    (in_bom yes) (on_board yes) (dnp no)
    (property "Reference" "R58" (at 40.64 195.58 0)
      (effects (font (size 1.27 1.27) (thickness 0.15)))
    )
    (property "Value" "R_2k2_0402" (at 63.5 209.55 0)
      (effects (font (size 1.27 1.27) (thickness 0.15)) (justify left bottom) hide)
    )
    (property "Footprint" "antmicro-footprints:R_0402_1005Metric" (at 63.5 212.09 0)
      (effects (font (size 1.27 1.27) (thickness 0.15)) (justify left bottom) hide)
    )
    (property "Datasheet" "https://www.bourns.com/docs/product-datasheets/cr.pdf" (at 63.5 214.63 0)
      (effects (font (size 1.27 1.27) (thickness 0.15)) (justify left bottom) hide)
    )
    (property "MPN" "CR0402-FX-2201GLF" (at 63.5 217.17 0)
      (effects (font (size 1.27 1.27) (thickness 0.15)) (justify left bottom) hide)
    )
    (property "Manufacturer" "Bourns" (at 63.5 219.71 0)
      (effects (font (size 1.27 1.27) (thickness 0.15)) (justify left bottom) hide)
    )
    (property "License" "Apache-2.0" (at 63.5 222.25 0)
      (effects (font (size 1.27 1.27) (thickness 0.15)) (justify left bottom) hide)
    )
    (property "Val" "2k2" (at 47.625 196.215 0)
      (effects (font (size 1.27 1.27) (thickness 0.15)) (justify left bottom))
    )
    (property "Tolerance" "1%" (at 63.5 207.01 0)
      (effects (font (size 1.27 1.27)) (justify left bottom) hide)
    )
    (property "Author" "Antmicro" (at 63.5 224.79 0)
      (effects (font (size 1.27 1.27) (thickness 0.15)) (justify left bottom) hide)
    )
    (pin "1")
    (pin "2")
    (instances
      (project "thunderbolt-pcie-adapter"
        (path ""
          (reference "R58") (unit 1)
        )
      )
    )
  )

  (symbol (lib_id "antmicroResistors0402:R_2k2_0402") (at 43.18 252.73 0) (unit 1)
    (in_bom yes) (on_board yes) (dnp no)
    (property "Reference" "R62" (at 41.275 251.46 0)
      (effects (font (size 1.27 1.27) (thickness 0.15)))
    )
    (property "Value" "R_2k2_0402" (at 63.5 265.43 0)
      (effects (font (size 1.27 1.27) (thickness 0.15)) (justify left bottom) hide)
    )
    (property "Footprint" "antmicro-footprints:R_0402_1005Metric" (at 63.5 267.97 0)
      (effects (font (size 1.27 1.27) (thickness 0.15)) (justify left bottom) hide)
    )
    (property "Datasheet" "https://www.bourns.com/docs/product-datasheets/cr.pdf" (at 63.5 270.51 0)
      (effects (font (size 1.27 1.27) (thickness 0.15)) (justify left bottom) hide)
    )
    (property "MPN" "CR0402-FX-2201GLF" (at 63.5 273.05 0)
      (effects (font (size 1.27 1.27) (thickness 0.15)) (justify left bottom) hide)
    )
    (property "Manufacturer" "Bourns" (at 63.5 275.59 0)
      (effects (font (size 1.27 1.27) (thickness 0.15)) (justify left bottom) hide)
    )
    (property "License" "Apache-2.0" (at 63.5 278.13 0)
      (effects (font (size 1.27 1.27) (thickness 0.15)) (justify left bottom) hide)
    )
    (property "Val" "2k2" (at 48.26 252.095 0)
      (effects (font (size 1.27 1.27) (thickness 0.15)) (justify left bottom))
    )
    (property "Tolerance" "1%" (at 63.5 262.89 0)
      (effects (font (size 1.27 1.27)) (justify left bottom) hide)
    )
    (property "Author" "Antmicro" (at 63.5 280.67 0)
      (effects (font (size 1.27 1.27) (thickness 0.15)) (justify left bottom) hide)
    )
    (pin "1")
    (pin "2")
    (instances
      (project "thunderbolt-pcie-adapter"
        (path ""
          (reference "R62") (unit 1)
        )
      )
    )
  )

  (symbol (lib_id "antmicropower:GND") (at 307.34 49.53 270) (unit 1)
    (in_bom yes) (on_board yes) (dnp no)
    (property "Reference" "#PWR0137" (at 300.99 49.53 0)
      (effects (font (size 1.27 1.27)) hide)
    )
    (property "Value" "GND" (at 302.895 47.625 0)
      (effects (font (size 1.27 1.27) (thickness 0.15)) (justify left bottom))
    )
    (property "Footprint" "" (at 307.34 49.53 0)
      (effects (font (size 1.27 1.27) (thickness 0.15)) (justify left bottom) hide)
    )
    (property "Datasheet" "" (at 307.34 49.53 0)
      (effects (font (size 1.27 1.27) (thickness 0.15)) (justify left bottom) hide)
    )
    (property "Author" "Antmicro" (at 299.72 58.42 0)
      (effects (font (size 1.27 1.27) (thickness 0.15)) (justify left bottom) hide)
    )
    (property "License" "Apache-2.0" (at 297.18 58.42 0)
      (effects (font (size 1.27 1.27) (thickness 0.15)) (justify left bottom) hide)
    )
    (pin "1")
    (instances
      (project "thunderbolt-pcie-adapter"
        (path ""
          (reference "#PWR0137") (unit 1)
        )
      )
    )
  )

  (symbol (lib_id "antmicroMemory:MX25L8006EM2I-12G") (at 294.64 229.87 0) (mirror y) (unit 1)
    (in_bom yes) (on_board yes) (dnp yes) (fields_autoplaced)
    (property "Reference" "U7" (at 281.94 222.25 0)
      (effects (font (size 1.27 1.27) (thickness 0.15)))
    )
    (property "Value" "MX25L8006EM2I-12G" (at 292.1 226.06 0)
      (effects (font (size 1.27 1.27) (thickness 0.15)) (justify left bottom) hide)
    )
    (property "Footprint" "antmicro-footprints:SOIC-8_5.3x5.3x2mm_P1.27mm" (at 259.08 234.95 0)
      (effects (font (size 1.27 1.27) (thickness 0.15)) (justify left bottom) hide)
    )
    (property "Datasheet" "https://www.macronix.com/Lists/Datasheet/Attachments/8680/MX25L8006E,%203V,%208Mb,%20v1.6.pdf" (at 259.08 237.49 0)
      (effects (font (size 1.27 1.27) (thickness 0.15)) (justify left bottom) hide)
    )
    (property "MPN" "MX25L8006EM2I-12G" (at 281.94 224.79 0)
      (effects (font (size 1.27 1.27) (thickness 0.15)))
    )
    (property "Manufacturer" "Macronix" (at 259.08 242.57 0)
      (effects (font (size 1.27 1.27) (thickness 0.15)) (justify left bottom) hide)
    )
    (property "Author" "Antmicro" (at 259.08 245.11 0)
      (effects (font (size 1.27 1.27) (thickness 0.15)) (justify left bottom) hide)
    )
    (property "License" "Apache-2.0" (at 259.08 247.65 0)
      (effects (font (size 1.27 1.27) (thickness 0.15)) (justify left bottom) hide)
    )
    (pin "1")
    (pin "2")
    (pin "3")
    (pin "4")
    (pin "5")
    (pin "6")
    (pin "7")
    (pin "8")
    (instances
      (project "thunderbolt-pcie-adapter"
        (path ""
          (reference "U7") (unit 1)
        )
      )
    )
  )

  (symbol (lib_id "antmicroCapacitors0402:C_220n_0402") (at 44.45 55.88 0) (unit 1)
    (in_bom yes) (on_board yes) (dnp no)
    (property "Reference" "C99" (at 44.45 54.61 0)
      (effects (font (size 1.27 1.27) (thickness 0.15)))
    )
    (property "Value" "C_220n_0402" (at 64.77 66.04 0)
      (effects (font (size 1.27 1.27) (thickness 0.15)) (justify left bottom) hide)
    )
    (property "Footprint" "antmicro-footprints:C_0402_1005Metric" (at 64.77 68.58 0)
      (effects (font (size 1.27 1.27) (thickness 0.15)) (justify left bottom) hide)
    )
    (property "Datasheet" "https://www.yageo.com/en/Chart/Download/pdf/CC0402KRX5R6BB224" (at 64.77 71.12 0)
      (effects (font (size 1.27 1.27) (thickness 0.15)) (justify left bottom) hide)
    )
    (property "MPN" "CC0402KRX5R6BB224" (at 64.77 73.66 0)
      (effects (font (size 1.27 1.27) (thickness 0.15)) (justify left bottom) hide)
    )
    (property "Manufacturer" "YAGEO" (at 64.77 76.2 0)
      (effects (font (size 1.27 1.27) (thickness 0.15)) (justify left bottom) hide)
    )
    (property "License" "Apache-2.0" (at 64.77 78.74 0)
      (effects (font (size 1.27 1.27) (thickness 0.15)) (justify left bottom) hide)
    )
    (property "Val" "220n" (at 47.625 55.245 0)
      (effects (font (size 1.27 1.27) (thickness 0.15)) (justify left bottom))
    )
    (property "Voltage" "" (at 64.77 83.82 0)
      (effects (font (size 1.27 1.27)) (justify left bottom) hide)
    )
    (property "Dielectric" "" (at 64.77 86.36 0)
      (effects (font (size 1.27 1.27)) (justify left bottom) hide)
    )
    (property "Author" "Antmicro" (at 64.77 81.28 0)
      (effects (font (size 1.27 1.27) (thickness 0.15)) (justify left bottom) hide)
    )
    (pin "1")
    (pin "2")
    (instances
      (project "thunderbolt-pcie-adapter"
        (path ""
          (reference "C99") (unit 1)
        )
      )
    )
  )

  (symbol (lib_id "antmicroCapacitors0402:C_10p_0402") (at 309.88 60.96 0) (unit 1)
    (in_bom yes) (on_board yes) (dnp no)
    (property "Reference" "C114" (at 312.42 58.42 0)
      (effects (font (size 1.27 1.27) (thickness 0.15)))
    )
    (property "Value" "C_10p_0402" (at 330.2 71.12 0)
      (effects (font (size 1.27 1.27) (thickness 0.15)) (justify left bottom) hide)
    )
    (property "Footprint" "antmicro-footprints:C_0402_1005Metric" (at 330.2 73.66 0)
      (effects (font (size 1.27 1.27) (thickness 0.15)) (justify left bottom) hide)
    )
    (property "Datasheet" "https://www.murata.com/products/productdetail?partno=GCM1555C1H100GA16%23" (at 330.2 76.2 0)
      (effects (font (size 1.27 1.27) (thickness 0.15)) (justify left bottom) hide)
    )
    (property "MPN" "GCM1555C1H100GA16D" (at 330.2 78.74 0)
      (effects (font (size 1.27 1.27) (thickness 0.15)) (justify left bottom) hide)
    )
    (property "Manufacturer" "Murata" (at 330.2 81.28 0)
      (effects (font (size 1.27 1.27) (thickness 0.15)) (justify left bottom) hide)
    )
    (property "License" "Apache-2.0" (at 330.2 83.82 0)
      (effects (font (size 1.27 1.27) (thickness 0.15)) (justify left bottom) hide)
    )
    (property "Val" "10p" (at 310.515 64.77 0)
      (effects (font (size 1.27 1.27) (thickness 0.15)) (justify left bottom))
    )
    (property "Voltage" "50V" (at 330.2 88.9 0)
      (effects (font (size 1.27 1.27)) (justify left bottom) hide)
    )
    (property "Dielectric" "C0G" (at 330.2 91.44 0)
      (effects (font (size 1.27 1.27)) (justify left bottom) hide)
    )
    (property "Author" "Antmicro" (at 330.2 86.36 0)
      (effects (font (size 1.27 1.27) (thickness 0.15)) (justify left bottom) hide)
    )
    (pin "1")
    (pin "2")
    (instances
      (project "thunderbolt-pcie-adapter"
        (path ""
          (reference "C114") (unit 1)
        )
      )
    )
  )

  (symbol (lib_id "antmicropower:GND") (at 266.7 242.57 0) (unit 1)
    (in_bom yes) (on_board yes) (dnp no)
    (property "Reference" "#PWR0128" (at 266.7 248.92 0)
      (effects (font (size 1.27 1.27)) hide)
    )
    (property "Value" "GND" (at 266.7 246.38 0)
      (effects (font (size 1.27 1.27) (thickness 0.15)) (justify left bottom))
    )
    (property "Footprint" "" (at 266.7 242.57 0)
      (effects (font (size 1.27 1.27) (thickness 0.15)) (justify left bottom) hide)
    )
    (property "Datasheet" "" (at 266.7 242.57 0)
      (effects (font (size 1.27 1.27) (thickness 0.15)) (justify left bottom) hide)
    )
    (property "Author" "Antmicro" (at 275.59 250.19 0)
      (effects (font (size 1.27 1.27) (thickness 0.15)) (justify left bottom) hide)
    )
    (property "License" "Apache-2.0" (at 275.59 252.73 0)
      (effects (font (size 1.27 1.27) (thickness 0.15)) (justify left bottom) hide)
    )
    (pin "1")
    (instances
      (project "thunderbolt-pcie-adapter"
        (path ""
          (reference "#PWR0128") (unit 1)
        )
      )
    )
  )

  (symbol (lib_id "antmicroCapacitors0402:C_220n_0402") (at 259.08 49.53 0) (unit 1)
    (in_bom yes) (on_board yes) (dnp no)
    (property "Reference" "C105" (at 252.095 48.26 0)
      (effects (font (size 1.27 1.27) (thickness 0.15)))
    )
    (property "Value" "C_220n_0402" (at 279.4 59.69 0)
      (effects (font (size 1.27 1.27) (thickness 0.15)) (justify left bottom) hide)
    )
    (property "Footprint" "antmicro-footprints:C_0402_1005Metric" (at 279.4 62.23 0)
      (effects (font (size 1.27 1.27) (thickness 0.15)) (justify left bottom) hide)
    )
    (property "Datasheet" "https://www.yageo.com/en/Chart/Download/pdf/CC0402KRX5R6BB224" (at 279.4 64.77 0)
      (effects (font (size 1.27 1.27) (thickness 0.15)) (justify left bottom) hide)
    )
    (property "MPN" "CC0402KRX5R6BB224" (at 279.4 67.31 0)
      (effects (font (size 1.27 1.27) (thickness 0.15)) (justify left bottom) hide)
    )
    (property "Manufacturer" "YAGEO" (at 279.4 69.85 0)
      (effects (font (size 1.27 1.27) (thickness 0.15)) (justify left bottom) hide)
    )
    (property "License" "Apache-2.0" (at 279.4 72.39 0)
      (effects (font (size 1.27 1.27) (thickness 0.15)) (justify left bottom) hide)
    )
    (property "Val" "220n" (at 255.27 48.895 0)
      (effects (font (size 1.27 1.27) (thickness 0.15)) (justify left bottom))
    )
    (property "Voltage" "" (at 279.4 77.47 0)
      (effects (font (size 1.27 1.27)) (justify left bottom) hide)
    )
    (property "Dielectric" "" (at 279.4 80.01 0)
      (effects (font (size 1.27 1.27)) (justify left bottom) hide)
    )
    (property "Author" "Antmicro" (at 279.4 74.93 0)
      (effects (font (size 1.27 1.27) (thickness 0.15)) (justify left bottom) hide)
    )
    (pin "1")
    (pin "2")
    (instances
      (project "thunderbolt-pcie-adapter"
        (path ""
          (reference "C105") (unit 1)
        )
      )
    )
  )

  (symbol (lib_id "antmicroCapacitors0402:C_220n_0402") (at 50.8 58.42 0) (unit 1)
    (in_bom yes) (on_board yes) (dnp no)
    (property "Reference" "C102" (at 56.515 57.15 0)
      (effects (font (size 1.27 1.27) (thickness 0.15)))
    )
    (property "Value" "C_220n_0402" (at 71.12 68.58 0)
      (effects (font (size 1.27 1.27) (thickness 0.15)) (justify left bottom) hide)
    )
    (property "Footprint" "antmicro-footprints:C_0402_1005Metric" (at 71.12 71.12 0)
      (effects (font (size 1.27 1.27) (thickness 0.15)) (justify left bottom) hide)
    )
    (property "Datasheet" "https://www.yageo.com/en/Chart/Download/pdf/CC0402KRX5R6BB224" (at 71.12 73.66 0)
      (effects (font (size 1.27 1.27) (thickness 0.15)) (justify left bottom) hide)
    )
    (property "MPN" "CC0402KRX5R6BB224" (at 71.12 76.2 0)
      (effects (font (size 1.27 1.27) (thickness 0.15)) (justify left bottom) hide)
    )
    (property "Manufacturer" "YAGEO" (at 71.12 78.74 0)
      (effects (font (size 1.27 1.27) (thickness 0.15)) (justify left bottom) hide)
    )
    (property "License" "Apache-2.0" (at 71.12 81.28 0)
      (effects (font (size 1.27 1.27) (thickness 0.15)) (justify left bottom) hide)
    )
    (property "Val" "220n" (at 59.69 57.785 0)
      (effects (font (size 1.27 1.27) (thickness 0.15)) (justify left bottom))
    )
    (property "Voltage" "" (at 71.12 86.36 0)
      (effects (font (size 1.27 1.27)) (justify left bottom) hide)
    )
    (property "Dielectric" "" (at 71.12 88.9 0)
      (effects (font (size 1.27 1.27)) (justify left bottom) hide)
    )
    (property "Author" "Antmicro" (at 71.12 83.82 0)
      (effects (font (size 1.27 1.27) (thickness 0.15)) (justify left bottom) hide)
    )
    (pin "1")
    (pin "2")
    (instances
      (project "thunderbolt-pcie-adapter"
        (path ""
          (reference "C102") (unit 1)
        )
      )
    )
  )

  (symbol (lib_id "antmicroResistors0402:R_3k3_0402") (at 299.72 224.79 90) (unit 1)
    (in_bom yes) (on_board yes) (dnp no)
    (property "Reference" "R50" (at 300.99 220.98 90)
      (effects (font (size 1.27 1.27) (thickness 0.15)) (justify right))
    )
    (property "Value" "R_3k3_0402" (at 312.42 204.47 0)
      (effects (font (size 1.27 1.27) (thickness 0.15)) (justify left bottom) hide)
    )
    (property "Footprint" "antmicro-footprints:R_0402_1005Metric" (at 314.96 204.47 0)
      (effects (font (size 1.27 1.27) (thickness 0.15)) (justify left bottom) hide)
    )
    (property "Datasheet" "https://www.bourns.com/docs/product-datasheets/cr.pdf" (at 317.5 204.47 0)
      (effects (font (size 1.27 1.27) (thickness 0.15)) (justify left bottom) hide)
    )
    (property "MPN" "CR0402-FX-3301GLF" (at 320.04 204.47 0)
      (effects (font (size 1.27 1.27) (thickness 0.15)) (justify left bottom) hide)
    )
    (property "Manufacturer" "Bourns" (at 322.58 204.47 0)
      (effects (font (size 1.27 1.27) (thickness 0.15)) (justify left bottom) hide)
    )
    (property "License" "Apache-2.0" (at 325.12 204.47 0)
      (effects (font (size 1.27 1.27) (thickness 0.15)) (justify left bottom) hide)
    )
    (property "Val" "3k3" (at 304.8 222.25 90)
      (effects (font (size 1.27 1.27) (thickness 0.15)) (justify left bottom))
    )
    (property "Tolerance" "1%" (at 309.88 204.47 0)
      (effects (font (size 1.27 1.27)) (justify left bottom) hide)
    )
    (property "Author" "Antmicro" (at 327.66 204.47 0)
      (effects (font (size 1.27 1.27) (thickness 0.15)) (justify left bottom) hide)
    )
    (pin "1")
    (pin "2")
    (instances
      (project "thunderbolt-pcie-adapter"
        (path ""
          (reference "R50") (unit 1)
        )
      )
    )
  )

  (symbol (lib_id "antmicropower:GND") (at 123.19 198.12 0) (unit 1)
    (in_bom yes) (on_board yes) (dnp no)
    (property "Reference" "#PWR0142" (at 123.19 204.47 0)
      (effects (font (size 1.27 1.27)) hide)
    )
    (property "Value" "GND" (at 121.285 202.565 0)
      (effects (font (size 1.27 1.27) (thickness 0.15)) (justify left bottom))
    )
    (property "Footprint" "" (at 123.19 198.12 0)
      (effects (font (size 1.27 1.27) (thickness 0.15)) (justify left bottom) hide)
    )
    (property "Datasheet" "" (at 123.19 198.12 0)
      (effects (font (size 1.27 1.27) (thickness 0.15)) (justify left bottom) hide)
    )
    (property "Author" "Antmicro" (at 132.08 205.74 0)
      (effects (font (size 1.27 1.27) (thickness 0.15)) (justify left bottom) hide)
    )
    (property "License" "Apache-2.0" (at 132.08 208.28 0)
      (effects (font (size 1.27 1.27) (thickness 0.15)) (justify left bottom) hide)
    )
    (pin "1")
    (instances
      (project "thunderbolt-pcie-adapter"
        (path ""
          (reference "#PWR0142") (unit 1)
        )
      )
    )
  )

  (symbol (lib_id "antmicroResistors0402:R_100k_0402") (at 111.76 237.49 0) (unit 1)
    (in_bom yes) (on_board yes) (dnp no)
    (property "Reference" "R84" (at 110.49 236.22 0)
      (effects (font (size 1.27 1.27) (thickness 0.15)))
    )
    (property "Value" "R_100k_0402" (at 132.08 250.19 0)
      (effects (font (size 1.27 1.27) (thickness 0.15)) (justify left bottom) hide)
    )
    (property "Footprint" "antmicro-footprints:R_0402_1005Metric" (at 132.08 252.73 0)
      (effects (font (size 1.27 1.27) (thickness 0.15)) (justify left bottom) hide)
    )
    (property "Datasheet" "https://www.bourns.com/docs/product-datasheets/cr.pdf" (at 132.08 255.27 0)
      (effects (font (size 1.27 1.27) (thickness 0.15)) (justify left bottom) hide)
    )
    (property "MPN" "CR0402-FX-1003GLF" (at 132.08 257.81 0)
      (effects (font (size 1.27 1.27) (thickness 0.15)) (justify left bottom) hide)
    )
    (property "Manufacturer" "Bourns" (at 132.08 260.35 0)
      (effects (font (size 1.27 1.27) (thickness 0.15)) (justify left bottom) hide)
    )
    (property "License" "Apache-2.0" (at 132.08 262.89 0)
      (effects (font (size 1.27 1.27) (thickness 0.15)) (justify left bottom) hide)
    )
    (property "Val" "100k" (at 116.84 236.855 0)
      (effects (font (size 1.27 1.27) (thickness 0.15)) (justify left bottom))
    )
    (property "Tolerance" "1%" (at 132.08 247.65 0)
      (effects (font (size 1.27 1.27)) (justify left bottom) hide)
    )
    (property "Author" "Antmicro" (at 132.08 265.43 0)
      (effects (font (size 1.27 1.27) (thickness 0.15)) (justify left bottom) hide)
    )
    (pin "1")
    (pin "2")
    (instances
      (project "thunderbolt-pcie-adapter"
        (path ""
          (reference "R84") (unit 1)
        )
      )
    )
  )

  (symbol (lib_id "antmicroMemory:MX25L8006EM1I-12G") (at 238.76 229.87 0) (unit 1)
    (in_bom yes) (on_board yes) (dnp no) (fields_autoplaced)
    (property "Reference" "U5" (at 251.46 222.25 0)
      (effects (font (size 1.27 1.27) (thickness 0.15)))
    )
    (property "Value" "MX25L8006EM1I-12G" (at 274.32 232.41 0)
      (effects (font (size 1.27 1.27) (thickness 0.15)) (justify left bottom) hide)
    )
    (property "Footprint" "antmicro-footprints:SOIC-8_3.9x4.9x1.75mm_P1.27mm" (at 274.32 234.95 0)
      (effects (font (size 1.27 1.27) (thickness 0.15)) (justify left bottom) hide)
    )
    (property "Datasheet" "https://www.macronix.com/Lists/Datasheet/Attachments/8680/MX25L8006E,%203V,%208Mb,%20v1.6.pdf" (at 274.32 237.49 0)
      (effects (font (size 1.27 1.27) (thickness 0.15)) (justify left bottom) hide)
    )
    (property "MPN" "MX25L8006EM1I-12G" (at 251.46 224.79 0)
      (effects (font (size 1.27 1.27) (thickness 0.15)))
    )
    (property "Manufacturer" "Macronix" (at 274.32 242.57 0)
      (effects (font (size 1.27 1.27) (thickness 0.15)) (justify left bottom) hide)
    )
    (property "License" "Apache-2.0" (at 274.32 247.65 0)
      (effects (font (size 1.27 1.27) (thickness 0.15)) (justify left bottom) hide)
    )
    (property "Author" "Antmicro" (at 274.32 245.11 0)
      (effects (font (size 1.27 1.27) (thickness 0.15)) (justify left bottom) hide)
    )
    (pin "1")
    (pin "2")
    (pin "3")
    (pin "4")
    (pin "5")
    (pin "6")
    (pin "7")
    (pin "8")
    (instances
      (project "thunderbolt-pcie-adapter"
        (path ""
          (reference "U5") (unit 1)
        )
      )
    )
  )

  (symbol (lib_id "antmicroCapacitors0402:C_10p_0402") (at 392.43 162.56 0) (unit 1)
    (in_bom yes) (on_board yes) (dnp no)
    (property "Reference" "C117" (at 394.97 160.02 0)
      (effects (font (size 1.27 1.27) (thickness 0.15)))
    )
    (property "Value" "C_10p_0402" (at 412.75 172.72 0)
      (effects (font (size 1.27 1.27) (thickness 0.15)) (justify left bottom) hide)
    )
    (property "Footprint" "antmicro-footprints:C_0402_1005Metric" (at 412.75 175.26 0)
      (effects (font (size 1.27 1.27) (thickness 0.15)) (justify left bottom) hide)
    )
    (property "Datasheet" "https://www.murata.com/products/productdetail?partno=GCM1555C1H100GA16%23" (at 412.75 177.8 0)
      (effects (font (size 1.27 1.27) (thickness 0.15)) (justify left bottom) hide)
    )
    (property "MPN" "GCM1555C1H100GA16D" (at 412.75 180.34 0)
      (effects (font (size 1.27 1.27) (thickness 0.15)) (justify left bottom) hide)
    )
    (property "Manufacturer" "Murata" (at 412.75 182.88 0)
      (effects (font (size 1.27 1.27) (thickness 0.15)) (justify left bottom) hide)
    )
    (property "License" "Apache-2.0" (at 412.75 185.42 0)
      (effects (font (size 1.27 1.27) (thickness 0.15)) (justify left bottom) hide)
    )
    (property "Val" "10p" (at 393.065 166.37 0)
      (effects (font (size 1.27 1.27) (thickness 0.15)) (justify left bottom))
    )
    (property "Voltage" "50V" (at 412.75 190.5 0)
      (effects (font (size 1.27 1.27)) (justify left bottom) hide)
    )
    (property "Dielectric" "C0G" (at 412.75 193.04 0)
      (effects (font (size 1.27 1.27)) (justify left bottom) hide)
    )
    (property "Author" "Antmicro" (at 412.75 187.96 0)
      (effects (font (size 1.27 1.27) (thickness 0.15)) (justify left bottom) hide)
    )
    (pin "1")
    (pin "2")
    (instances
      (project "thunderbolt-pcie-adapter"
        (path ""
          (reference "C117") (unit 1)
        )
      )
    )
  )

  (symbol (lib_id "antmicropower:GND") (at 66.04 100.33 0) (mirror y) (unit 1)
    (in_bom yes) (on_board yes) (dnp no)
    (property "Reference" "#PWR0134" (at 66.04 106.68 0)
      (effects (font (size 1.27 1.27)) hide)
    )
    (property "Value" "GND" (at 67.945 104.775 0)
      (effects (font (size 1.27 1.27) (thickness 0.15)) (justify left bottom))
    )
    (property "Footprint" "" (at 66.04 100.33 0)
      (effects (font (size 1.27 1.27) (thickness 0.15)) (justify left bottom) hide)
    )
    (property "Datasheet" "" (at 66.04 100.33 0)
      (effects (font (size 1.27 1.27) (thickness 0.15)) (justify left bottom) hide)
    )
    (property "Author" "Antmicro" (at 57.15 107.95 0)
      (effects (font (size 1.27 1.27) (thickness 0.15)) (justify left bottom) hide)
    )
    (property "License" "Apache-2.0" (at 57.15 110.49 0)
      (effects (font (size 1.27 1.27) (thickness 0.15)) (justify left bottom) hide)
    )
    (pin "1")
    (instances
      (project "thunderbolt-pcie-adapter"
        (path ""
          (reference "#PWR0134") (unit 1)
        )
      )
    )
  )

  (symbol (lib_id "antmicropower:GND") (at 52.07 100.33 0) (unit 1)
    (in_bom yes) (on_board yes) (dnp no)
    (property "Reference" "#PWR0130" (at 52.07 106.68 0)
      (effects (font (size 1.27 1.27)) hide)
    )
    (property "Value" "GND" (at 50.165 104.775 0)
      (effects (font (size 1.27 1.27) (thickness 0.15)) (justify left bottom))
    )
    (property "Footprint" "" (at 52.07 100.33 0)
      (effects (font (size 1.27 1.27) (thickness 0.15)) (justify left bottom) hide)
    )
    (property "Datasheet" "" (at 52.07 100.33 0)
      (effects (font (size 1.27 1.27) (thickness 0.15)) (justify left bottom) hide)
    )
    (property "Author" "Antmicro" (at 60.96 107.95 0)
      (effects (font (size 1.27 1.27) (thickness 0.15)) (justify left bottom) hide)
    )
    (property "License" "Apache-2.0" (at 60.96 110.49 0)
      (effects (font (size 1.27 1.27) (thickness 0.15)) (justify left bottom) hide)
    )
    (pin "1")
    (instances
      (project "thunderbolt-pcie-adapter"
        (path ""
          (reference "#PWR0130") (unit 1)
        )
      )
    )
  )

  (symbol (lib_id "antmicroResistors0402:R_4k75_0.5%_0402") (at 299.72 166.37 90) (unit 1)
    (in_bom yes) (on_board yes) (dnp no)
    (property "Reference" "R69" (at 294.005 162.56 90)
      (effects (font (size 1.27 1.27) (thickness 0.15)) (justify right))
    )
    (property "Value" "R_4k75_0.5%_0402" (at 312.42 146.05 0)
      (effects (font (size 1.27 1.27) (thickness 0.15)) (justify left bottom) hide)
    )
    (property "Footprint" "antmicro-footprints:R_0402_1005Metric" (at 314.96 146.05 0)
      (effects (font (size 1.27 1.27) (thickness 0.15)) (justify left bottom) hide)
    )
    (property "Datasheet" "https://industrial.panasonic.com/cdbs/www-data/pdf/RDQ0000/ast-ind-151033.pdf" (at 317.5 146.05 0)
      (effects (font (size 1.27 1.27) (thickness 0.15)) (justify left bottom) hide)
    )
    (property "MPN" "ERJ-H2RD4751X" (at 320.04 146.05 0)
      (effects (font (size 1.27 1.27) (thickness 0.15)) (justify left bottom) hide)
    )
    (property "Manufacturer" "Panasonic" (at 322.58 146.05 0)
      (effects (font (size 1.27 1.27) (thickness 0.15)) (justify left bottom) hide)
    )
    (property "License" "Apache-2.0" (at 325.12 146.05 0)
      (effects (font (size 1.27 1.27) (thickness 0.15)) (justify left bottom) hide)
    )
    (property "Val" "4k75" (at 293.37 164.465 90)
      (effects (font (size 1.27 1.27) (thickness 0.15)) (justify right))
    )
    (property "Tolerance" "0.5%" (at 298.45 165.1 90)
      (effects (font (size 1.27 1.27)) (justify left bottom) hide)
    )
    (property "Author" "Antmicro" (at 327.66 146.05 0)
      (effects (font (size 1.27 1.27) (thickness 0.15)) (justify left bottom) hide)
    )
    (pin "1")
    (pin "2")
    (instances
      (project "thunderbolt-pcie-adapter"
        (path ""
          (reference "R69") (unit 1)
        )
      )
    )
  )

  (symbol (lib_id "antmicroResistors0402:R_10k_0402") (at 111.76 217.17 0) (unit 1)
    (in_bom yes) (on_board yes) (dnp no)
    (property "Reference" "R79" (at 110.49 215.9 0)
      (effects (font (size 1.27 1.27) (thickness 0.15)))
    )
    (property "Value" "R_10k_0402" (at 132.08 229.87 0)
      (effects (font (size 1.27 1.27) (thickness 0.15)) (justify left bottom) hide)
    )
    (property "Footprint" "antmicro-footprints:R_0402_1005Metric" (at 132.08 232.41 0)
      (effects (font (size 1.27 1.27) (thickness 0.15)) (justify left bottom) hide)
    )
    (property "Datasheet" "https://www.bourns.com/docs/product-datasheets/cr.pdf" (at 132.08 234.95 0)
      (effects (font (size 1.27 1.27) (thickness 0.15)) (justify left bottom) hide)
    )
    (property "MPN" "CR0402-FX-1002GLF" (at 132.08 237.49 0)
      (effects (font (size 1.27 1.27) (thickness 0.15)) (justify left bottom) hide)
    )
    (property "Manufacturer" "Bourns" (at 132.08 240.03 0)
      (effects (font (size 1.27 1.27) (thickness 0.15)) (justify left bottom) hide)
    )
    (property "License" "Apache-2.0" (at 132.08 242.57 0)
      (effects (font (size 1.27 1.27) (thickness 0.15)) (justify left bottom) hide)
    )
    (property "Val" "10k" (at 116.205 216.535 0)
      (effects (font (size 1.27 1.27) (thickness 0.15)) (justify left bottom))
    )
    (property "Tolerance" "1%" (at 132.08 227.33 0)
      (effects (font (size 1.27 1.27)) (justify left bottom) hide)
    )
    (property "Author" "Antmicro" (at 132.08 245.11 0)
      (effects (font (size 1.27 1.27) (thickness 0.15)) (justify left bottom) hide)
    )
    (pin "1")
    (pin "2")
    (instances
      (project "thunderbolt-pcie-adapter"
        (path ""
          (reference "R79") (unit 1)
        )
      )
    )
  )

  (symbol (lib_id "antmicroResistors0402:R_10k_0402") (at 293.37 147.32 0) (unit 1)
    (in_bom yes) (on_board yes) (dnp no)
    (property "Reference" "R65" (at 291.465 146.05 0)
      (effects (font (size 1.27 1.27) (thickness 0.15)))
    )
    (property "Value" "R_10k_0402" (at 313.69 160.02 0)
      (effects (font (size 1.27 1.27) (thickness 0.15)) (justify left bottom) hide)
    )
    (property "Footprint" "antmicro-footprints:R_0402_1005Metric" (at 313.69 162.56 0)
      (effects (font (size 1.27 1.27) (thickness 0.15)) (justify left bottom) hide)
    )
    (property "Datasheet" "https://www.bourns.com/docs/product-datasheets/cr.pdf" (at 313.69 165.1 0)
      (effects (font (size 1.27 1.27) (thickness 0.15)) (justify left bottom) hide)
    )
    (property "MPN" "CR0402-FX-1002GLF" (at 313.69 167.64 0)
      (effects (font (size 1.27 1.27) (thickness 0.15)) (justify left bottom) hide)
    )
    (property "Manufacturer" "Bourns" (at 313.69 170.18 0)
      (effects (font (size 1.27 1.27) (thickness 0.15)) (justify left bottom) hide)
    )
    (property "License" "Apache-2.0" (at 313.69 172.72 0)
      (effects (font (size 1.27 1.27) (thickness 0.15)) (justify left bottom) hide)
    )
    (property "Val" "10k" (at 298.45 146.685 0)
      (effects (font (size 1.27 1.27) (thickness 0.15)) (justify left bottom))
    )
    (property "Tolerance" "1%" (at 313.69 157.48 0)
      (effects (font (size 1.27 1.27)) (justify left bottom) hide)
    )
    (property "Author" "Antmicro" (at 313.69 175.26 0)
      (effects (font (size 1.27 1.27) (thickness 0.15)) (justify left bottom) hide)
    )
    (pin "1")
    (pin "2")
    (instances
      (project "thunderbolt-pcie-adapter"
        (path ""
          (reference "R65") (unit 1)
        )
      )
    )
  )

  (symbol (lib_id "antmicroResistors0402:R_10k_0402") (at 111.76 214.63 0) (unit 1)
    (in_bom yes) (on_board yes) (dnp no)
    (property "Reference" "R78" (at 110.49 213.36 0)
      (effects (font (size 1.27 1.27) (thickness 0.15)))
    )
    (property "Value" "R_10k_0402" (at 132.08 227.33 0)
      (effects (font (size 1.27 1.27) (thickness 0.15)) (justify left bottom) hide)
    )
    (property "Footprint" "antmicro-footprints:R_0402_1005Metric" (at 132.08 229.87 0)
      (effects (font (size 1.27 1.27) (thickness 0.15)) (justify left bottom) hide)
    )
    (property "Datasheet" "https://www.bourns.com/docs/product-datasheets/cr.pdf" (at 132.08 232.41 0)
      (effects (font (size 1.27 1.27) (thickness 0.15)) (justify left bottom) hide)
    )
    (property "MPN" "CR0402-FX-1002GLF" (at 132.08 234.95 0)
      (effects (font (size 1.27 1.27) (thickness 0.15)) (justify left bottom) hide)
    )
    (property "Manufacturer" "Bourns" (at 132.08 237.49 0)
      (effects (font (size 1.27 1.27) (thickness 0.15)) (justify left bottom) hide)
    )
    (property "License" "Apache-2.0" (at 132.08 240.03 0)
      (effects (font (size 1.27 1.27) (thickness 0.15)) (justify left bottom) hide)
    )
    (property "Val" "10k" (at 116.205 213.995 0)
      (effects (font (size 1.27 1.27) (thickness 0.15)) (justify left bottom))
    )
    (property "Tolerance" "1%" (at 132.08 224.79 0)
      (effects (font (size 1.27 1.27)) (justify left bottom) hide)
    )
    (property "Author" "Antmicro" (at 132.08 242.57 0)
      (effects (font (size 1.27 1.27) (thickness 0.15)) (justify left bottom) hide)
    )
    (pin "1")
    (pin "2")
    (instances
      (project "thunderbolt-pcie-adapter"
        (path ""
          (reference "R78") (unit 1)
        )
      )
    )
  )

  (symbol (lib_id "antmicroResistors0402:R_3k3_0402") (at 306.07 224.79 90) (unit 1)
    (in_bom yes) (on_board yes) (dnp no)
    (property "Reference" "R51" (at 307.34 220.98 90)
      (effects (font (size 1.27 1.27) (thickness 0.15)) (justify right))
    )
    (property "Value" "R_3k3_0402" (at 318.77 204.47 0)
      (effects (font (size 1.27 1.27) (thickness 0.15)) (justify left bottom) hide)
    )
    (property "Footprint" "antmicro-footprints:R_0402_1005Metric" (at 321.31 204.47 0)
      (effects (font (size 1.27 1.27) (thickness 0.15)) (justify left bottom) hide)
    )
    (property "Datasheet" "https://www.bourns.com/docs/product-datasheets/cr.pdf" (at 323.85 204.47 0)
      (effects (font (size 1.27 1.27) (thickness 0.15)) (justify left bottom) hide)
    )
    (property "MPN" "CR0402-FX-3301GLF" (at 326.39 204.47 0)
      (effects (font (size 1.27 1.27) (thickness 0.15)) (justify left bottom) hide)
    )
    (property "Manufacturer" "Bourns" (at 328.93 204.47 0)
      (effects (font (size 1.27 1.27) (thickness 0.15)) (justify left bottom) hide)
    )
    (property "License" "Apache-2.0" (at 331.47 204.47 0)
      (effects (font (size 1.27 1.27) (thickness 0.15)) (justify left bottom) hide)
    )
    (property "Val" "3k3" (at 311.15 222.25 90)
      (effects (font (size 1.27 1.27) (thickness 0.15)) (justify left bottom))
    )
    (property "Tolerance" "1%" (at 316.23 204.47 0)
      (effects (font (size 1.27 1.27)) (justify left bottom) hide)
    )
    (property "Author" "Antmicro" (at 334.01 204.47 0)
      (effects (font (size 1.27 1.27) (thickness 0.15)) (justify left bottom) hide)
    )
    (pin "1")
    (pin "2")
    (instances
      (project "thunderbolt-pcie-adapter"
        (path ""
          (reference "R51") (unit 1)
        )
      )
    )
  )

  (symbol (lib_id "antmicropower:GND") (at 335.28 48.26 0) (unit 1)
    (in_bom yes) (on_board yes) (dnp no)
    (property "Reference" "#PWR0147" (at 335.28 54.61 0)
      (effects (font (size 1.27 1.27)) hide)
    )
    (property "Value" "GND" (at 333.375 52.705 0)
      (effects (font (size 1.27 1.27) (thickness 0.15)) (justify left bottom))
    )
    (property "Footprint" "" (at 335.28 48.26 0)
      (effects (font (size 1.27 1.27) (thickness 0.15)) (justify left bottom) hide)
    )
    (property "Datasheet" "" (at 335.28 48.26 0)
      (effects (font (size 1.27 1.27) (thickness 0.15)) (justify left bottom) hide)
    )
    (property "Author" "Antmicro" (at 344.17 55.88 0)
      (effects (font (size 1.27 1.27) (thickness 0.15)) (justify left bottom) hide)
    )
    (property "License" "Apache-2.0" (at 344.17 58.42 0)
      (effects (font (size 1.27 1.27) (thickness 0.15)) (justify left bottom) hide)
    )
    (pin "1")
    (instances
      (project "thunderbolt-pcie-adapter"
        (path ""
          (reference "#PWR0147") (unit 1)
        )
      )
    )
  )

  (symbol (lib_id "antmicropower:GND") (at 179.07 175.26 0) (unit 1)
    (in_bom yes) (on_board yes) (dnp no)
    (property "Reference" "#PWR0135" (at 179.07 181.61 0)
      (effects (font (size 1.27 1.27)) hide)
    )
    (property "Value" "GND" (at 177.165 180.34 0)
      (effects (font (size 1.27 1.27) (thickness 0.15)) (justify left bottom))
    )
    (property "Footprint" "" (at 179.07 175.26 0)
      (effects (font (size 1.27 1.27) (thickness 0.15)) (justify left bottom) hide)
    )
    (property "Datasheet" "" (at 179.07 175.26 0)
      (effects (font (size 1.27 1.27) (thickness 0.15)) (justify left bottom) hide)
    )
    (property "Author" "Antmicro" (at 187.96 182.88 0)
      (effects (font (size 1.27 1.27) (thickness 0.15)) (justify left bottom) hide)
    )
    (property "License" "Apache-2.0" (at 187.96 185.42 0)
      (effects (font (size 1.27 1.27) (thickness 0.15)) (justify left bottom) hide)
    )
    (pin "1")
    (instances
      (project "thunderbolt-pcie-adapter"
        (path ""
          (reference "#PWR0135") (unit 1)
        )
      )
    )
  )

  (symbol (lib_id "antmicropower:GND") (at 373.38 149.86 0) (unit 1)
    (in_bom yes) (on_board yes) (dnp no)
    (property "Reference" "#PWR0144" (at 373.38 156.21 0)
      (effects (font (size 1.27 1.27)) hide)
    )
    (property "Value" "GND" (at 371.475 154.305 0)
      (effects (font (size 1.27 1.27) (thickness 0.15)) (justify left bottom))
    )
    (property "Footprint" "" (at 373.38 149.86 0)
      (effects (font (size 1.27 1.27) (thickness 0.15)) (justify left bottom) hide)
    )
    (property "Datasheet" "" (at 373.38 149.86 0)
      (effects (font (size 1.27 1.27) (thickness 0.15)) (justify left bottom) hide)
    )
    (property "Author" "Antmicro" (at 382.27 157.48 0)
      (effects (font (size 1.27 1.27) (thickness 0.15)) (justify left bottom) hide)
    )
    (property "License" "Apache-2.0" (at 382.27 160.02 0)
      (effects (font (size 1.27 1.27) (thickness 0.15)) (justify left bottom) hide)
    )
    (pin "1")
    (instances
      (project "thunderbolt-pcie-adapter"
        (path ""
          (reference "#PWR0144") (unit 1)
        )
      )
    )
  )

  (symbol (lib_id "antmicropower:GND") (at 146.05 100.33 0) (unit 1)
    (in_bom yes) (on_board yes) (dnp no)
    (property "Reference" "#PWR0139" (at 146.05 106.68 0)
      (effects (font (size 1.27 1.27)) hide)
    )
    (property "Value" "GND" (at 144.145 104.775 0)
      (effects (font (size 1.27 1.27) (thickness 0.15)) (justify left bottom))
    )
    (property "Footprint" "" (at 146.05 100.33 0)
      (effects (font (size 1.27 1.27) (thickness 0.15)) (justify left bottom) hide)
    )
    (property "Datasheet" "" (at 146.05 100.33 0)
      (effects (font (size 1.27 1.27) (thickness 0.15)) (justify left bottom) hide)
    )
    (property "Author" "Antmicro" (at 154.94 107.95 0)
      (effects (font (size 1.27 1.27) (thickness 0.15)) (justify left bottom) hide)
    )
    (property "License" "Apache-2.0" (at 154.94 110.49 0)
      (effects (font (size 1.27 1.27) (thickness 0.15)) (justify left bottom) hide)
    )
    (pin "1")
    (instances
      (project "thunderbolt-pcie-adapter"
        (path ""
          (reference "#PWR0139") (unit 1)
        )
      )
    )
  )

  (symbol (lib_id "antmicroResistors0402:R_10k_0402") (at 111.76 219.71 0) (unit 1)
    (in_bom yes) (on_board yes) (dnp no)
    (property "Reference" "R80" (at 110.49 218.44 0)
      (effects (font (size 1.27 1.27) (thickness 0.15)))
    )
    (property "Value" "R_10k_0402" (at 132.08 232.41 0)
      (effects (font (size 1.27 1.27) (thickness 0.15)) (justify left bottom) hide)
    )
    (property "Footprint" "antmicro-footprints:R_0402_1005Metric" (at 132.08 234.95 0)
      (effects (font (size 1.27 1.27) (thickness 0.15)) (justify left bottom) hide)
    )
    (property "Datasheet" "https://www.bourns.com/docs/product-datasheets/cr.pdf" (at 132.08 237.49 0)
      (effects (font (size 1.27 1.27) (thickness 0.15)) (justify left bottom) hide)
    )
    (property "MPN" "CR0402-FX-1002GLF" (at 132.08 240.03 0)
      (effects (font (size 1.27 1.27) (thickness 0.15)) (justify left bottom) hide)
    )
    (property "Manufacturer" "Bourns" (at 132.08 242.57 0)
      (effects (font (size 1.27 1.27) (thickness 0.15)) (justify left bottom) hide)
    )
    (property "License" "Apache-2.0" (at 132.08 245.11 0)
      (effects (font (size 1.27 1.27) (thickness 0.15)) (justify left bottom) hide)
    )
    (property "Val" "10k" (at 116.205 219.075 0)
      (effects (font (size 1.27 1.27) (thickness 0.15)) (justify left bottom))
    )
    (property "Tolerance" "1%" (at 132.08 229.87 0)
      (effects (font (size 1.27 1.27)) (justify left bottom) hide)
    )
    (property "Author" "Antmicro" (at 132.08 247.65 0)
      (effects (font (size 1.27 1.27) (thickness 0.15)) (justify left bottom) hide)
    )
    (pin "1")
    (pin "2")
    (instances
      (project "thunderbolt-pcie-adapter"
        (path ""
          (reference "R80") (unit 1)
        )
      )
    )
  )

  (symbol (lib_id "antmicroResistors0402:R_1M_0402") (at 55.88 97.79 90) (unit 1)
    (in_bom yes) (on_board yes) (dnp no)
    (property "Reference" "R55" (at 59.055 94.615 90)
      (effects (font (size 1.27 1.27) (thickness 0.15)))
    )
    (property "Value" "R_1M_0402" (at 68.58 77.47 0)
      (effects (font (size 1.27 1.27) (thickness 0.15)) (justify left bottom) hide)
    )
    (property "Footprint" "antmicro-footprints:R_0402_1005Metric" (at 71.12 77.47 0)
      (effects (font (size 1.27 1.27) (thickness 0.15)) (justify left bottom) hide)
    )
    (property "Datasheet" "https://www.bourns.com/docs/product-datasheets/cr.pdf" (at 73.66 77.47 0)
      (effects (font (size 1.27 1.27) (thickness 0.15)) (justify left bottom) hide)
    )
    (property "MPN" "CR0402-FX-1004GLF" (at 76.2 77.47 0)
      (effects (font (size 1.27 1.27) (thickness 0.15)) (justify left bottom) hide)
    )
    (property "Manufacturer" "Bourns" (at 78.74 77.47 0)
      (effects (font (size 1.27 1.27) (thickness 0.15)) (justify left bottom) hide)
    )
    (property "License" "Apache-2.0" (at 81.28 77.47 0)
      (effects (font (size 1.27 1.27) (thickness 0.15)) (justify left bottom) hide)
    )
    (property "Val" "1M" (at 60.325 95.885 90)
      (effects (font (size 1.27 1.27) (thickness 0.15)) (justify left bottom))
    )
    (property "Tolerance" "1%" (at 66.04 77.47 0)
      (effects (font (size 1.27 1.27)) (justify left bottom) hide)
    )
    (property "Author" "Antmicro" (at 83.82 77.47 0)
      (effects (font (size 1.27 1.27) (thickness 0.15)) (justify left bottom) hide)
    )
    (pin "1")
    (pin "2")
    (instances
      (project "thunderbolt-pcie-adapter"
        (path ""
          (reference "R55") (unit 1)
        )
      )
    )
  )

  (symbol (lib_id "antmicroCapacitors0402:C_220n_0402") (at 50.8 66.04 0) (unit 1)
    (in_bom yes) (on_board yes) (dnp no)
    (property "Reference" "C103" (at 56.515 64.77 0)
      (effects (font (size 1.27 1.27) (thickness 0.15)))
    )
    (property "Value" "C_220n_0402" (at 71.12 76.2 0)
      (effects (font (size 1.27 1.27) (thickness 0.15)) (justify left bottom) hide)
    )
    (property "Footprint" "antmicro-footprints:C_0402_1005Metric" (at 71.12 78.74 0)
      (effects (font (size 1.27 1.27) (thickness 0.15)) (justify left bottom) hide)
    )
    (property "Datasheet" "https://www.yageo.com/en/Chart/Download/pdf/CC0402KRX5R6BB224" (at 71.12 81.28 0)
      (effects (font (size 1.27 1.27) (thickness 0.15)) (justify left bottom) hide)
    )
    (property "MPN" "CC0402KRX5R6BB224" (at 71.12 83.82 0)
      (effects (font (size 1.27 1.27) (thickness 0.15)) (justify left bottom) hide)
    )
    (property "Manufacturer" "YAGEO" (at 71.12 86.36 0)
      (effects (font (size 1.27 1.27) (thickness 0.15)) (justify left bottom) hide)
    )
    (property "License" "Apache-2.0" (at 71.12 88.9 0)
      (effects (font (size 1.27 1.27) (thickness 0.15)) (justify left bottom) hide)
    )
    (property "Val" "220n" (at 59.69 65.405 0)
      (effects (font (size 1.27 1.27) (thickness 0.15)) (justify left bottom))
    )
    (property "Voltage" "" (at 71.12 93.98 0)
      (effects (font (size 1.27 1.27)) (justify left bottom) hide)
    )
    (property "Dielectric" "" (at 71.12 96.52 0)
      (effects (font (size 1.27 1.27)) (justify left bottom) hide)
    )
    (property "Author" "Antmicro" (at 71.12 91.44 0)
      (effects (font (size 1.27 1.27) (thickness 0.15)) (justify left bottom) hide)
    )
    (pin "1")
    (pin "2")
    (instances
      (project "thunderbolt-pcie-adapter"
        (path ""
          (reference "C103") (unit 1)
        )
      )
    )
  )

  (symbol (lib_id "antmicroResistors0402:R_1M_0402") (at 134.62 86.36 0) (unit 1)
    (in_bom yes) (on_board yes) (dnp no)
    (property "Reference" "R70" (at 133.35 85.09 0)
      (effects (font (size 1.27 1.27) (thickness 0.15)))
    )
    (property "Value" "R_1M_0402" (at 154.94 99.06 0)
      (effects (font (size 1.27 1.27) (thickness 0.15)) (justify left bottom) hide)
    )
    (property "Footprint" "antmicro-footprints:R_0402_1005Metric" (at 154.94 101.6 0)
      (effects (font (size 1.27 1.27) (thickness 0.15)) (justify left bottom) hide)
    )
    (property "Datasheet" "https://www.bourns.com/docs/product-datasheets/cr.pdf" (at 154.94 104.14 0)
      (effects (font (size 1.27 1.27) (thickness 0.15)) (justify left bottom) hide)
    )
    (property "MPN" "CR0402-FX-1004GLF" (at 154.94 106.68 0)
      (effects (font (size 1.27 1.27) (thickness 0.15)) (justify left bottom) hide)
    )
    (property "Manufacturer" "Bourns" (at 154.94 109.22 0)
      (effects (font (size 1.27 1.27) (thickness 0.15)) (justify left bottom) hide)
    )
    (property "License" "Apache-2.0" (at 154.94 111.76 0)
      (effects (font (size 1.27 1.27) (thickness 0.15)) (justify left bottom) hide)
    )
    (property "Val" "1M" (at 139.7 85.725 0)
      (effects (font (size 1.27 1.27) (thickness 0.15)) (justify left bottom))
    )
    (property "Tolerance" "1%" (at 154.94 96.52 0)
      (effects (font (size 1.27 1.27)) (justify left bottom) hide)
    )
    (property "Author" "Antmicro" (at 154.94 114.3 0)
      (effects (font (size 1.27 1.27) (thickness 0.15)) (justify left bottom) hide)
    )
    (pin "1")
    (pin "2")
    (instances
      (project "thunderbolt-pcie-adapter"
        (path ""
          (reference "R70") (unit 1)
        )
      )
    )
  )

  (symbol (lib_id "antmicroResistors0402:R_100k_0402") (at 43.18 191.77 0) (unit 1)
    (in_bom yes) (on_board yes) (dnp no)
    (property "Reference" "R57" (at 40.64 190.5 0)
      (effects (font (size 1.27 1.27) (thickness 0.15)))
    )
    (property "Value" "R_100k_0402" (at 63.5 204.47 0)
      (effects (font (size 1.27 1.27) (thickness 0.15)) (justify left bottom) hide)
    )
    (property "Footprint" "antmicro-footprints:R_0402_1005Metric" (at 63.5 207.01 0)
      (effects (font (size 1.27 1.27) (thickness 0.15)) (justify left bottom) hide)
    )
    (property "Datasheet" "https://www.bourns.com/docs/product-datasheets/cr.pdf" (at 63.5 209.55 0)
      (effects (font (size 1.27 1.27) (thickness 0.15)) (justify left bottom) hide)
    )
    (property "MPN" "CR0402-FX-1003GLF" (at 63.5 212.09 0)
      (effects (font (size 1.27 1.27) (thickness 0.15)) (justify left bottom) hide)
    )
    (property "Manufacturer" "Bourns" (at 63.5 214.63 0)
      (effects (font (size 1.27 1.27) (thickness 0.15)) (justify left bottom) hide)
    )
    (property "License" "Apache-2.0" (at 63.5 217.17 0)
      (effects (font (size 1.27 1.27) (thickness 0.15)) (justify left bottom) hide)
    )
    (property "Val" "100k" (at 47.625 191.135 0)
      (effects (font (size 1.27 1.27) (thickness 0.15)) (justify left bottom))
    )
    (property "Tolerance" "1%" (at 63.5 201.93 0)
      (effects (font (size 1.27 1.27)) (justify left bottom) hide)
    )
    (property "Author" "Antmicro" (at 63.5 219.71 0)
      (effects (font (size 1.27 1.27) (thickness 0.15)) (justify left bottom) hide)
    )
    (pin "1")
    (pin "2")
    (instances
      (project "thunderbolt-pcie-adapter"
        (path ""
          (reference "R57") (unit 1)
        )
      )
    )
  )

  (symbol (lib_id "antmicroCapacitors0402:C_220n_0402") (at 44.45 63.5 0) (unit 1)
    (in_bom yes) (on_board yes) (dnp no)
    (property "Reference" "C100" (at 43.815 62.23 0)
      (effects (font (size 1.27 1.27) (thickness 0.15)))
    )
    (property "Value" "C_220n_0402" (at 64.77 73.66 0)
      (effects (font (size 1.27 1.27) (thickness 0.15)) (justify left bottom) hide)
    )
    (property "Footprint" "antmicro-footprints:C_0402_1005Metric" (at 64.77 76.2 0)
      (effects (font (size 1.27 1.27) (thickness 0.15)) (justify left bottom) hide)
    )
    (property "Datasheet" "https://www.yageo.com/en/Chart/Download/pdf/CC0402KRX5R6BB224" (at 64.77 78.74 0)
      (effects (font (size 1.27 1.27) (thickness 0.15)) (justify left bottom) hide)
    )
    (property "MPN" "CC0402KRX5R6BB224" (at 64.77 81.28 0)
      (effects (font (size 1.27 1.27) (thickness 0.15)) (justify left bottom) hide)
    )
    (property "Manufacturer" "YAGEO" (at 64.77 83.82 0)
      (effects (font (size 1.27 1.27) (thickness 0.15)) (justify left bottom) hide)
    )
    (property "License" "Apache-2.0" (at 64.77 86.36 0)
      (effects (font (size 1.27 1.27) (thickness 0.15)) (justify left bottom) hide)
    )
    (property "Val" "220n" (at 47.625 62.865 0)
      (effects (font (size 1.27 1.27) (thickness 0.15)) (justify left bottom))
    )
    (property "Voltage" "" (at 64.77 91.44 0)
      (effects (font (size 1.27 1.27)) (justify left bottom) hide)
    )
    (property "Dielectric" "" (at 64.77 93.98 0)
      (effects (font (size 1.27 1.27)) (justify left bottom) hide)
    )
    (property "Author" "Antmicro" (at 64.77 88.9 0)
      (effects (font (size 1.27 1.27) (thickness 0.15)) (justify left bottom) hide)
    )
    (pin "1")
    (pin "2")
    (instances
      (project "thunderbolt-pcie-adapter"
        (path ""
          (reference "C100") (unit 1)
        )
      )
    )
  )

  (symbol (lib_id "antmicroResistors0402:R_10k_0402") (at 293.37 152.4 0) (unit 1)
    (in_bom yes) (on_board yes) (dnp no)
    (property "Reference" "R67" (at 291.465 151.13 0)
      (effects (font (size 1.27 1.27) (thickness 0.15)))
    )
    (property "Value" "R_10k_0402" (at 313.69 165.1 0)
      (effects (font (size 1.27 1.27) (thickness 0.15)) (justify left bottom) hide)
    )
    (property "Footprint" "antmicro-footprints:R_0402_1005Metric" (at 313.69 167.64 0)
      (effects (font (size 1.27 1.27) (thickness 0.15)) (justify left bottom) hide)
    )
    (property "Datasheet" "https://www.bourns.com/docs/product-datasheets/cr.pdf" (at 313.69 170.18 0)
      (effects (font (size 1.27 1.27) (thickness 0.15)) (justify left bottom) hide)
    )
    (property "MPN" "CR0402-FX-1002GLF" (at 313.69 172.72 0)
      (effects (font (size 1.27 1.27) (thickness 0.15)) (justify left bottom) hide)
    )
    (property "Manufacturer" "Bourns" (at 313.69 175.26 0)
      (effects (font (size 1.27 1.27) (thickness 0.15)) (justify left bottom) hide)
    )
    (property "License" "Apache-2.0" (at 313.69 177.8 0)
      (effects (font (size 1.27 1.27) (thickness 0.15)) (justify left bottom) hide)
    )
    (property "Val" "10k" (at 298.45 151.765 0)
      (effects (font (size 1.27 1.27) (thickness 0.15)) (justify left bottom))
    )
    (property "Tolerance" "1%" (at 313.69 162.56 0)
      (effects (font (size 1.27 1.27)) (justify left bottom) hide)
    )
    (property "Author" "Antmicro" (at 313.69 180.34 0)
      (effects (font (size 1.27 1.27) (thickness 0.15)) (justify left bottom) hide)
    )
    (pin "1")
    (pin "2")
    (instances
      (project "thunderbolt-pcie-adapter"
        (path ""
          (reference "R67") (unit 1)
        )
      )
    )
  )

  (symbol (lib_id "antmicroResistors0402:R_100k_0402") (at 111.76 222.25 0) (unit 1)
    (in_bom yes) (on_board yes) (dnp no)
    (property "Reference" "R81" (at 110.49 220.98 0)
      (effects (font (size 1.27 1.27) (thickness 0.15)))
    )
    (property "Value" "R_100k_0402" (at 132.08 234.95 0)
      (effects (font (size 1.27 1.27) (thickness 0.15)) (justify left bottom) hide)
    )
    (property "Footprint" "antmicro-footprints:R_0402_1005Metric" (at 132.08 237.49 0)
      (effects (font (size 1.27 1.27) (thickness 0.15)) (justify left bottom) hide)
    )
    (property "Datasheet" "https://www.bourns.com/docs/product-datasheets/cr.pdf" (at 132.08 240.03 0)
      (effects (font (size 1.27 1.27) (thickness 0.15)) (justify left bottom) hide)
    )
    (property "MPN" "CR0402-FX-1003GLF" (at 132.08 242.57 0)
      (effects (font (size 1.27 1.27) (thickness 0.15)) (justify left bottom) hide)
    )
    (property "Manufacturer" "Bourns" (at 132.08 245.11 0)
      (effects (font (size 1.27 1.27) (thickness 0.15)) (justify left bottom) hide)
    )
    (property "License" "Apache-2.0" (at 132.08 247.65 0)
      (effects (font (size 1.27 1.27) (thickness 0.15)) (justify left bottom) hide)
    )
    (property "Val" "100k" (at 116.205 221.615 0)
      (effects (font (size 1.27 1.27) (thickness 0.15)) (justify left bottom))
    )
    (property "Tolerance" "1%" (at 132.08 232.41 0)
      (effects (font (size 1.27 1.27)) (justify left bottom) hide)
    )
    (property "Author" "Antmicro" (at 132.08 250.19 0)
      (effects (font (size 1.27 1.27) (thickness 0.15)) (justify left bottom) hide)
    )
    (pin "1")
    (pin "2")
    (instances
      (project "thunderbolt-pcie-adapter"
        (path ""
          (reference "R81") (unit 1)
        )
      )
    )
  )

  (symbol (lib_id "antmicropower:GND") (at 39.37 259.08 0) (mirror y) (unit 1)
    (in_bom yes) (on_board yes) (dnp no)
    (property "Reference" "#PWR0133" (at 39.37 265.43 0)
      (effects (font (size 1.27 1.27)) hide)
    )
    (property "Value" "GND" (at 41.275 263.525 0)
      (effects (font (size 1.27 1.27) (thickness 0.15)) (justify left bottom))
    )
    (property "Footprint" "" (at 39.37 259.08 0)
      (effects (font (size 1.27 1.27) (thickness 0.15)) (justify left bottom) hide)
    )
    (property "Datasheet" "" (at 39.37 259.08 0)
      (effects (font (size 1.27 1.27) (thickness 0.15)) (justify left bottom) hide)
    )
    (property "Author" "Antmicro" (at 30.48 266.7 0)
      (effects (font (size 1.27 1.27) (thickness 0.15)) (justify left bottom) hide)
    )
    (property "License" "Apache-2.0" (at 30.48 269.24 0)
      (effects (font (size 1.27 1.27) (thickness 0.15)) (justify left bottom) hide)
    )
    (pin "1")
    (instances
      (project "thunderbolt-pcie-adapter"
        (path ""
          (reference "#PWR0133") (unit 1)
        )
      )
    )
  )

  (symbol (lib_id "antmicropower:GND") (at 55.88 100.33 0) (unit 1)
    (in_bom yes) (on_board yes) (dnp no)
    (property "Reference" "#PWR0131" (at 55.88 106.68 0)
      (effects (font (size 1.27 1.27)) hide)
    )
    (property "Value" "GND" (at 53.975 104.775 0)
      (effects (font (size 1.27 1.27) (thickness 0.15)) (justify left bottom))
    )
    (property "Footprint" "" (at 55.88 100.33 0)
      (effects (font (size 1.27 1.27) (thickness 0.15)) (justify left bottom) hide)
    )
    (property "Datasheet" "" (at 55.88 100.33 0)
      (effects (font (size 1.27 1.27) (thickness 0.15)) (justify left bottom) hide)
    )
    (property "Author" "Antmicro" (at 64.77 107.95 0)
      (effects (font (size 1.27 1.27) (thickness 0.15)) (justify left bottom) hide)
    )
    (property "License" "Apache-2.0" (at 64.77 110.49 0)
      (effects (font (size 1.27 1.27) (thickness 0.15)) (justify left bottom) hide)
    )
    (pin "1")
    (instances
      (project "thunderbolt-pcie-adapter"
        (path ""
          (reference "#PWR0131") (unit 1)
        )
      )
    )
  )

  (symbol (lib_id "antmicroResistors0402:R_10k_0402") (at 111.76 240.03 0) (unit 1)
    (in_bom yes) (on_board yes) (dnp no)
    (property "Reference" "R85" (at 110.49 238.76 0)
      (effects (font (size 1.27 1.27) (thickness 0.15)))
    )
    (property "Value" "R_10k_0402" (at 132.08 252.73 0)
      (effects (font (size 1.27 1.27) (thickness 0.15)) (justify left bottom) hide)
    )
    (property "Footprint" "antmicro-footprints:R_0402_1005Metric" (at 132.08 255.27 0)
      (effects (font (size 1.27 1.27) (thickness 0.15)) (justify left bottom) hide)
    )
    (property "Datasheet" "https://www.bourns.com/docs/product-datasheets/cr.pdf" (at 132.08 257.81 0)
      (effects (font (size 1.27 1.27) (thickness 0.15)) (justify left bottom) hide)
    )
    (property "MPN" "CR0402-FX-1002GLF" (at 132.08 260.35 0)
      (effects (font (size 1.27 1.27) (thickness 0.15)) (justify left bottom) hide)
    )
    (property "Manufacturer" "Bourns" (at 132.08 262.89 0)
      (effects (font (size 1.27 1.27) (thickness 0.15)) (justify left bottom) hide)
    )
    (property "License" "Apache-2.0" (at 132.08 265.43 0)
      (effects (font (size 1.27 1.27) (thickness 0.15)) (justify left bottom) hide)
    )
    (property "Val" "10k" (at 116.84 239.395 0)
      (effects (font (size 1.27 1.27) (thickness 0.15)) (justify left bottom))
    )
    (property "Tolerance" "1%" (at 132.08 250.19 0)
      (effects (font (size 1.27 1.27)) (justify left bottom) hide)
    )
    (property "Author" "Antmicro" (at 132.08 267.97 0)
      (effects (font (size 1.27 1.27) (thickness 0.15)) (justify left bottom) hide)
    )
    (pin "1")
    (pin "2")
    (instances
      (project "thunderbolt-pcie-adapter"
        (path ""
          (reference "R85") (unit 1)
        )
      )
    )
  )

  (symbol (lib_id "antmicroCapacitors0402:C_100n_0402") (at 232.41 218.44 90) (unit 1)
    (in_bom yes) (on_board yes) (dnp no) (fields_autoplaced)
    (property "Reference" "C98" (at 234.95 214.6236 90)
      (effects (font (size 1.27 1.27) (thickness 0.15)) (justify right))
    )
    (property "Value" "C_100n_0402" (at 242.57 198.12 0)
      (effects (font (size 1.27 1.27) (thickness 0.15)) (justify left bottom) hide)
    )
    (property "Footprint" "antmicro-footprints:C_0402_1005Metric" (at 245.11 198.12 0)
      (effects (font (size 1.27 1.27) (thickness 0.15)) (justify left bottom) hide)
    )
    (property "Datasheet" "https://www.murata.com/products/productdetail?partno=GRM155R61H104KE14%23" (at 247.65 198.12 0)
      (effects (font (size 1.27 1.27) (thickness 0.15)) (justify left bottom) hide)
    )
    (property "MPN" "GRM155R61H104KE14D" (at 250.19 198.12 0)
      (effects (font (size 1.27 1.27) (thickness 0.15)) (justify left bottom) hide)
    )
    (property "Manufacturer" "Murata" (at 252.73 198.12 0)
      (effects (font (size 1.27 1.27) (thickness 0.15)) (justify left bottom) hide)
    )
    (property "License" "Apache-2.0" (at 255.27 198.12 0)
      (effects (font (size 1.27 1.27) (thickness 0.15)) (justify left bottom) hide)
    )
    (property "Val" "100n" (at 234.95 217.1636 90)
      (effects (font (size 1.27 1.27) (thickness 0.15)) (justify right))
    )
    (property "Voltage" "50V" (at 260.35 198.12 0)
      (effects (font (size 1.27 1.27)) (justify left bottom) hide)
    )
    (property "Dielectric" "X5R" (at 262.89 198.12 0)
      (effects (font (size 1.27 1.27)) (justify left bottom) hide)
    )
    (property "Author" "Antmicro" (at 257.81 198.12 0)
      (effects (font (size 1.27 1.27) (thickness 0.15)) (justify left bottom) hide)
    )
    (pin "1")
    (pin "2")
    (instances
      (project "thunderbolt-pcie-adapter"
        (path ""
          (reference "C98") (unit 1)
        )
      )
    )
  )

  (symbol (lib_id "antmicroResistors0402:R_1M_0402") (at 134.62 88.9 0) (unit 1)
    (in_bom yes) (on_board yes) (dnp no)
    (property "Reference" "R71" (at 133.35 87.63 0)
      (effects (font (size 1.27 1.27) (thickness 0.15)))
    )
    (property "Value" "R_1M_0402" (at 154.94 101.6 0)
      (effects (font (size 1.27 1.27) (thickness 0.15)) (justify left bottom) hide)
    )
    (property "Footprint" "antmicro-footprints:R_0402_1005Metric" (at 154.94 104.14 0)
      (effects (font (size 1.27 1.27) (thickness 0.15)) (justify left bottom) hide)
    )
    (property "Datasheet" "https://www.bourns.com/docs/product-datasheets/cr.pdf" (at 154.94 106.68 0)
      (effects (font (size 1.27 1.27) (thickness 0.15)) (justify left bottom) hide)
    )
    (property "MPN" "CR0402-FX-1004GLF" (at 154.94 109.22 0)
      (effects (font (size 1.27 1.27) (thickness 0.15)) (justify left bottom) hide)
    )
    (property "Manufacturer" "Bourns" (at 154.94 111.76 0)
      (effects (font (size 1.27 1.27) (thickness 0.15)) (justify left bottom) hide)
    )
    (property "License" "Apache-2.0" (at 154.94 114.3 0)
      (effects (font (size 1.27 1.27) (thickness 0.15)) (justify left bottom) hide)
    )
    (property "Val" "1M" (at 139.7 88.265 0)
      (effects (font (size 1.27 1.27) (thickness 0.15)) (justify left bottom))
    )
    (property "Tolerance" "1%" (at 154.94 99.06 0)
      (effects (font (size 1.27 1.27)) (justify left bottom) hide)
    )
    (property "Author" "Antmicro" (at 154.94 116.84 0)
      (effects (font (size 1.27 1.27) (thickness 0.15)) (justify left bottom) hide)
    )
    (pin "1")
    (pin "2")
    (instances
      (project "thunderbolt-pcie-adapter"
        (path ""
          (reference "R71") (unit 1)
        )
      )
    )
  )

  (symbol (lib_id "antmicroClockTimingClockGeneratorsPLLsFrequencySynthesizers:SI52112-B6-GT") (at 341.63 50.8 0) (unit 1)
    (in_bom yes) (on_board yes) (dnp no)
    (property "Reference" "U6" (at 353.695 43.815 0)
      (effects (font (size 1.27 1.27) (thickness 0.15)))
    )
    (property "Value" "SI52112-B6-GT" (at 379.73 55.88 0)
      (effects (font (size 1.27 1.27) (thickness 0.15)) (justify left bottom) hide)
    )
    (property "Footprint" "antmicro-footprints:TSSOP-8_3x4.4mm_P0.65mm" (at 379.73 58.42 0)
      (effects (font (size 1.27 1.27) (thickness 0.15)) (justify left bottom) hide)
    )
    (property "Datasheet" "https://www.skyworksinc.com/-/media/Skyworks/SL/documents/public/data-sheets/Si52112-B5-B6.pdf" (at 379.73 60.96 0)
      (effects (font (size 1.27 1.27) (thickness 0.15)) (justify left bottom) hide)
    )
    (property "MPN" "SI52112-B6-GT" (at 345.44 46.99 0)
      (effects (font (size 1.27 1.27) (thickness 0.15)) (justify left bottom))
    )
    (property "Manufacturer" "Skyworks Solutions" (at 379.73 66.04 0)
      (effects (font (size 1.27 1.27) (thickness 0.15)) (justify left bottom) hide)
    )
    (property "License" "Apache-2.0" (at 379.73 71.12 0)
      (effects (font (size 1.27 1.27) (thickness 0.15)) (justify left bottom) hide)
    )
    (property "Author" "Antmicro" (at 379.73 68.58 0)
      (effects (font (size 1.27 1.27) (thickness 0.15)) (justify left bottom) hide)
    )
    (pin "1")
    (pin "2")
    (pin "3")
    (pin "4")
    (pin "5")
    (pin "6")
    (pin "7")
    (pin "8")
    (instances
      (project "thunderbolt-pcie-adapter"
        (path ""
          (reference "U6") (unit 1)
        )
      )
    )
  )

  (symbol (lib_id "antmicroResistors0402:R_10k_0402") (at 293.37 149.86 0) (unit 1)
    (in_bom yes) (on_board yes) (dnp no)
    (property "Reference" "R66" (at 291.465 148.59 0)
      (effects (font (size 1.27 1.27) (thickness 0.15)))
    )
    (property "Value" "R_10k_0402" (at 313.69 162.56 0)
      (effects (font (size 1.27 1.27) (thickness 0.15)) (justify left bottom) hide)
    )
    (property "Footprint" "antmicro-footprints:R_0402_1005Metric" (at 313.69 165.1 0)
      (effects (font (size 1.27 1.27) (thickness 0.15)) (justify left bottom) hide)
    )
    (property "Datasheet" "https://www.bourns.com/docs/product-datasheets/cr.pdf" (at 313.69 167.64 0)
      (effects (font (size 1.27 1.27) (thickness 0.15)) (justify left bottom) hide)
    )
    (property "MPN" "CR0402-FX-1002GLF" (at 313.69 170.18 0)
      (effects (font (size 1.27 1.27) (thickness 0.15)) (justify left bottom) hide)
    )
    (property "Manufacturer" "Bourns" (at 313.69 172.72 0)
      (effects (font (size 1.27 1.27) (thickness 0.15)) (justify left bottom) hide)
    )
    (property "License" "Apache-2.0" (at 313.69 175.26 0)
      (effects (font (size 1.27 1.27) (thickness 0.15)) (justify left bottom) hide)
    )
    (property "Val" "10k" (at 298.45 149.225 0)
      (effects (font (size 1.27 1.27) (thickness 0.15)) (justify left bottom))
    )
    (property "Tolerance" "1%" (at 313.69 160.02 0)
      (effects (font (size 1.27 1.27)) (justify left bottom) hide)
    )
    (property "Author" "Antmicro" (at 313.69 177.8 0)
      (effects (font (size 1.27 1.27) (thickness 0.15)) (justify left bottom) hide)
    )
    (pin "1")
    (pin "2")
    (instances
      (project "thunderbolt-pcie-adapter"
        (path ""
          (reference "R66") (unit 1)
        )
      )
    )
  )

  (symbol (lib_id "antmicroResistors0402:R_100k_0402") (at 134.62 91.44 0) (unit 1)
    (in_bom yes) (on_board yes) (dnp no)
    (property "Reference" "R72" (at 133.35 90.17 0)
      (effects (font (size 1.27 1.27) (thickness 0.15)))
    )
    (property "Value" "R_100k_0402" (at 154.94 104.14 0)
      (effects (font (size 1.27 1.27) (thickness 0.15)) (justify left bottom) hide)
    )
    (property "Footprint" "antmicro-footprints:R_0402_1005Metric" (at 154.94 106.68 0)
      (effects (font (size 1.27 1.27) (thickness 0.15)) (justify left bottom) hide)
    )
    (property "Datasheet" "https://www.bourns.com/docs/product-datasheets/cr.pdf" (at 154.94 109.22 0)
      (effects (font (size 1.27 1.27) (thickness 0.15)) (justify left bottom) hide)
    )
    (property "MPN" "CR0402-FX-1003GLF" (at 154.94 111.76 0)
      (effects (font (size 1.27 1.27) (thickness 0.15)) (justify left bottom) hide)
    )
    (property "Manufacturer" "Bourns" (at 154.94 114.3 0)
      (effects (font (size 1.27 1.27) (thickness 0.15)) (justify left bottom) hide)
    )
    (property "License" "Apache-2.0" (at 154.94 116.84 0)
      (effects (font (size 1.27 1.27) (thickness 0.15)) (justify left bottom) hide)
    )
    (property "Val" "100k" (at 139.7 90.805 0)
      (effects (font (size 1.27 1.27) (thickness 0.15)) (justify left bottom))
    )
    (property "Tolerance" "1%" (at 154.94 101.6 0)
      (effects (font (size 1.27 1.27)) (justify left bottom) hide)
    )
    (property "Author" "Antmicro" (at 154.94 119.38 0)
      (effects (font (size 1.27 1.27) (thickness 0.15)) (justify left bottom) hide)
    )
    (pin "1")
    (pin "2")
    (instances
      (project "thunderbolt-pcie-adapter"
        (path ""
          (reference "R72") (unit 1)
        )
      )
    )
  )

  (symbol (lib_id "antmicropower:GND") (at 248.92 86.36 0) (unit 1)
    (in_bom yes) (on_board yes) (dnp no)
    (property "Reference" "#PWR0140" (at 248.92 92.71 0)
      (effects (font (size 1.27 1.27)) hide)
    )
    (property "Value" "GND" (at 247.015 90.805 0)
      (effects (font (size 1.27 1.27) (thickness 0.15)) (justify left bottom))
    )
    (property "Footprint" "" (at 248.92 86.36 0)
      (effects (font (size 1.27 1.27) (thickness 0.15)) (justify left bottom) hide)
    )
    (property "Datasheet" "" (at 248.92 86.36 0)
      (effects (font (size 1.27 1.27) (thickness 0.15)) (justify left bottom) hide)
    )
    (property "Author" "Antmicro" (at 257.81 93.98 0)
      (effects (font (size 1.27 1.27) (thickness 0.15)) (justify left bottom) hide)
    )
    (property "License" "Apache-2.0" (at 257.81 96.52 0)
      (effects (font (size 1.27 1.27) (thickness 0.15)) (justify left bottom) hide)
    )
    (pin "1")
    (instances
      (project "thunderbolt-pcie-adapter"
        (path ""
          (reference "#PWR0140") (unit 1)
        )
      )
    )
  )

  (symbol (lib_id "antmicroResistors0402:R_10k_0402") (at 111.76 234.95 0) (unit 1)
    (in_bom yes) (on_board yes) (dnp no)
    (property "Reference" "R83" (at 110.49 233.68 0)
      (effects (font (size 1.27 1.27) (thickness 0.15)))
    )
    (property "Value" "R_10k_0402" (at 132.08 247.65 0)
      (effects (font (size 1.27 1.27) (thickness 0.15)) (justify left bottom) hide)
    )
    (property "Footprint" "antmicro-footprints:R_0402_1005Metric" (at 132.08 250.19 0)
      (effects (font (size 1.27 1.27) (thickness 0.15)) (justify left bottom) hide)
    )
    (property "Datasheet" "https://www.bourns.com/docs/product-datasheets/cr.pdf" (at 132.08 252.73 0)
      (effects (font (size 1.27 1.27) (thickness 0.15)) (justify left bottom) hide)
    )
    (property "MPN" "CR0402-FX-1002GLF" (at 132.08 255.27 0)
      (effects (font (size 1.27 1.27) (thickness 0.15)) (justify left bottom) hide)
    )
    (property "Manufacturer" "Bourns" (at 132.08 257.81 0)
      (effects (font (size 1.27 1.27) (thickness 0.15)) (justify left bottom) hide)
    )
    (property "License" "Apache-2.0" (at 132.08 260.35 0)
      (effects (font (size 1.27 1.27) (thickness 0.15)) (justify left bottom) hide)
    )
    (property "Val" "10k" (at 116.84 234.315 0)
      (effects (font (size 1.27 1.27) (thickness 0.15)) (justify left bottom))
    )
    (property "Tolerance" "1%" (at 132.08 245.11 0)
      (effects (font (size 1.27 1.27)) (justify left bottom) hide)
    )
    (property "Author" "Antmicro" (at 132.08 262.89 0)
      (effects (font (size 1.27 1.27) (thickness 0.15)) (justify left bottom) hide)
    )
    (pin "1")
    (pin "2")
    (instances
      (project "thunderbolt-pcie-adapter"
        (path ""
          (reference "R83") (unit 1)
        )
      )
    )
  )

  (symbol (lib_id "antmicropower:GND") (at 238.76 172.72 0) (unit 1)
    (in_bom yes) (on_board yes) (dnp no)
    (property "Reference" "#PWR0136" (at 238.76 179.07 0)
      (effects (font (size 1.27 1.27)) hide)
    )
    (property "Value" "GND" (at 236.855 177.8 0)
      (effects (font (size 1.27 1.27) (thickness 0.15)) (justify left bottom))
    )
    (property "Footprint" "" (at 238.76 172.72 0)
      (effects (font (size 1.27 1.27) (thickness 0.15)) (justify left bottom) hide)
    )
    (property "Datasheet" "" (at 238.76 172.72 0)
      (effects (font (size 1.27 1.27) (thickness 0.15)) (justify left bottom) hide)
    )
    (property "Author" "Antmicro" (at 247.65 180.34 0)
      (effects (font (size 1.27 1.27) (thickness 0.15)) (justify left bottom) hide)
    )
    (property "License" "Apache-2.0" (at 247.65 182.88 0)
      (effects (font (size 1.27 1.27) (thickness 0.15)) (justify left bottom) hide)
    )
    (pin "1")
    (instances
      (project "thunderbolt-pcie-adapter"
        (path ""
          (reference "#PWR0136") (unit 1)
        )
      )
    )
  )

  (symbol (lib_id "antmicroInterfaceControllers:JHL6340SLLSQ") (at 52.07 153.67 0) (unit 3)
    (in_bom yes) (on_board yes) (dnp no) (fields_autoplaced)
    (property "Reference" "U4" (at 80.01 144.78 0)
      (effects (font (size 1.27 1.27) (thickness 0.15)))
    )
    (property "Value" "JHL6340SLLSQ" (at 123.19 156.21 0)
      (effects (font (size 1.27 1.27) (thickness 0.15)) (justify left bottom) hide)
    )
    (property "Footprint" "antmicro-footprints:JHL6340SLLSQ" (at 123.19 158.75 0)
      (effects (font (size 1.27 1.27) (thickness 0.15)) (justify left bottom) hide)
    )
    (property "Datasheet" "https://www.thunderbolttechnology.net/sites/default/files/18-241_ThunderboltController_Brief_HI.pdf" (at 123.19 161.29 0)
      (effects (font (size 1.27 1.27) (thickness 0.15)) (justify left bottom) hide)
    )
    (property "Manufacturer" "Intel" (at 123.19 163.83 0)
      (effects (font (size 1.27 1.27) (thickness 0.15)) (justify left bottom) hide)
    )
    (property "MPN" "JHL6340SLLSQ" (at 80.01 147.32 0)
      (effects (font (size 1.27 1.27) (thickness 0.15)))
    )
    (property "Author" "Antmicro" (at 123.19 168.91 0)
      (effects (font (size 1.27 1.27) (thickness 0.15)) (justify left bottom) hide)
    )
    (property "License" "Apache-2.0" (at 123.19 171.45 0)
      (effects (font (size 1.27 1.27) (thickness 0.15)) (justify left bottom) hide)
    )
    (pin "A1")
    (pin "A10")
    (pin "A12")
    (pin "A14")
    (pin "A16")
    (pin "A18")
    (pin "A2")
    (pin "A20")
    (pin "A22")
    (pin "A3")
    (pin "A6")
    (pin "A8")
    (pin "AA22")
    (pin "AA23")
    (pin "AB1")
    (pin "AB10")
    (pin "AB12")
    (pin "AB14")
    (pin "AB16")
    (pin "AB18")
    (pin "AB20")
    (pin "AB22")
    (pin "AB6")
    (pin "AB8")
    (pin "AC10")
    (pin "AC12")
    (pin "AC14")
    (pin "AC16")
    (pin "AC18")
    (pin "AC2")
    (pin "AC20")
    (pin "AC22")
    (pin "AC6")
    (pin "AC8")
    (pin "B1")
    (pin "B10")
    (pin "B12")
    (pin "B14")
    (pin "B16")
    (pin "B18")
    (pin "B2")
    (pin "B20")
    (pin "B22")
    (pin "B3")
    (pin "B6")
    (pin "B8")
    (pin "C1")
    (pin "C2")
    (pin "D1")
    (pin "D11")
    (pin "D12")
    (pin "D13")
    (pin "D15")
    (pin "D16")
    (pin "D18")
    (pin "D5")
    (pin "D8")
    (pin "D9")
    (pin "E11")
    (pin "E12")
    (pin "E13")
    (pin "E15")
    (pin "E16")
    (pin "E22")
    (pin "E23")
    (pin "E4")
    (pin "E5")
    (pin "E6")
    (pin "E8")
    (pin "E9")
    (pin "F11")
    (pin "F12")
    (pin "F13")
    (pin "F15")
    (pin "F16")
    (pin "F18")
    (pin "F20")
    (pin "F5")
    (pin "F6")
    (pin "F8")
    (pin "F9")
    (pin "G22")
    (pin "G23")
    (pin "H1")
    (pin "H11")
    (pin "H12")
    (pin "H13")
    (pin "H15")
    (pin "H16")
    (pin "H18")
    (pin "H2")
    (pin "H20")
    (pin "H5")
    (pin "H8")
    (pin "H9")
    (pin "J11")
    (pin "J12")
    (pin "J13")
    (pin "J15")
    (pin "J16")
    (pin "J18")
    (pin "J19")
    (pin "J20")
    (pin "J22")
    (pin "J23")
    (pin "J5")
    (pin "J8")
    (pin "J9")
    (pin "K1")
    (pin "K2")
    (pin "L11")
    (pin "L12")
    (pin "L13")
    (pin "L16")
    (pin "L18")
    (pin "L19")
    (pin "L20")
    (pin "L22")
    (pin "L23")
    (pin "L5")
    (pin "L6")
    (pin "L8")
    (pin "L9")
    (pin "M1")
    (pin "M11")
    (pin "M12")
    (pin "M13")
    (pin "M15")
    (pin "M16")
    (pin "M18")
    (pin "M19")
    (pin "M2")
    (pin "M20")
    (pin "M5")
    (pin "M6")
    (pin "M8")
    (pin "M9")
    (pin "N11")
    (pin "N12")
    (pin "N13")
    (pin "N18")
    (pin "N19")
    (pin "N20")
    (pin "N22")
    (pin "N23")
    (pin "N5")
    (pin "N8")
    (pin "N9")
    (pin "P1")
    (pin "P2")
    (pin "R11")
    (pin "R12")
    (pin "R13")
    (pin "R15")
    (pin "R16")
    (pin "R18")
    (pin "R19")
    (pin "R20")
    (pin "R22")
    (pin "R23")
    (pin "R5")
    (pin "R6")
    (pin "R8")
    (pin "R9")
    (pin "T1")
    (pin "T11")
    (pin "T12")
    (pin "T13")
    (pin "T15")
    (pin "T16")
    (pin "T18")
    (pin "T2")
    (pin "T20")
    (pin "T5")
    (pin "T6")
    (pin "T8")
    (pin "T9")
    (pin "U22")
    (pin "U23")
    (pin "V11")
    (pin "V12")
    (pin "V13")
    (pin "V15")
    (pin "V16")
    (pin "V20")
    (pin "V5")
    (pin "V6")
    (pin "V8")
    (pin "V9")
    (pin "W20")
    (pin "W22")
    (pin "W23")
    (pin "W5")
    (pin "W6")
    (pin "W8")
    (pin "W9")
    (pin "Y13")
    (pin "Y20")
    (pin "Y9")
    (pin "AC5")
    (pin "F22")
    (pin "F23")
    (pin "H22")
    (pin "H23")
    (pin "K22")
    (pin "K23")
    (pin "L4")
    (pin "M22")
    (pin "M23")
    (pin "N16")
    (pin "P22")
    (pin "P23")
    (pin "T19")
    (pin "T22")
    (pin "T23")
    (pin "V19")
    (pin "V22")
    (pin "V23")
    (pin "Y22")
    (pin "Y23")
    (pin "AA1")
    (pin "AA2")
    (pin "AB11")
    (pin "AB13")
    (pin "AB15")
    (pin "AB17")
    (pin "AB19")
    (pin "AB21")
    (pin "AB7")
    (pin "AB9")
    (pin "AC11")
    (pin "AC13")
    (pin "AC15")
    (pin "AC17")
    (pin "AC19")
    (pin "AC21")
    (pin "AC7")
    (pin "AC9")
    (pin "D2")
    (pin "D4")
    (pin "E2")
    (pin "F1")
    (pin "F2")
    (pin "G1")
    (pin "H4")
    (pin "J1")
    (pin "J2")
    (pin "J4")
    (pin "L1")
    (pin "L2")
    (pin "N1")
    (pin "N2")
    (pin "N4")
    (pin "N6")
    (pin "R1")
    (pin "R2")
    (pin "R4")
    (pin "U1")
    (pin "U2")
    (pin "V1")
    (pin "V2")
    (pin "W1")
    (pin "W11")
    (pin "W12")
    (pin "W19")
    (pin "W2")
    (pin "Y1")
    (pin "Y11")
    (pin "Y12")
    (pin "Y18")
    (pin "Y19")
    (pin "Y2")
    (pin "Y5")
    (pin "Y6")
    (pin "Y8")
    (pin "AB3")
    (pin "AB4")
    (pin "AB5")
    (pin "AC3")
    (pin "AC4")
    (pin "D22")
    (pin "D23")
    (pin "E1")
    (pin "F4")
    (pin "H6")
    (pin "J6")
    (pin "T4")
    (pin "V4")
    (pin "W4")
    (pin "Y4")
    (pin "A11")
    (pin "A13")
    (pin "A15")
    (pin "A17")
    (pin "A19")
    (pin "A21")
    (pin "A4")
    (pin "A5")
    (pin "A7")
    (pin "A9")
    (pin "B11")
    (pin "B13")
    (pin "B15")
    (pin "B17")
    (pin "B19")
    (pin "B21")
    (pin "B4")
    (pin "B5")
    (pin "B7")
    (pin "B9")
    (pin "D19")
    (pin "D20")
    (pin "E19")
    (pin "E20")
    (pin "F19")
    (pin "G2")
    (pin "H19")
    (pin "M4")
    (pin "W15")
    (pin "W16")
    (pin "Y15")
    (pin "Y16")
    (pin "A23")
    (pin "AB2")
    (pin "AB23")
    (pin "AC1")
    (pin "AC23")
    (pin "B23")
    (pin "C22")
    (pin "C23")
    (pin "D6")
    (pin "E18")
    (pin "L15")
    (pin "N15")
    (pin "V18")
    (pin "W13")
    (pin "W18")
    (instances
      (project "thunderbolt-pcie-adapter"
        (path ""
          (reference "U4") (unit 3)
        )
      )
    )
  )

  (symbol (lib_id "antmicroResistors0402:R_14k_0402") (at 111.76 196.85 0) (unit 1)
    (in_bom yes) (on_board yes) (dnp yes)
    (property "Reference" "R76" (at 109.22 195.58 0)
      (effects (font (size 1.27 1.27) (thickness 0.15)))
    )
    (property "Value" "R_14k_0402" (at 132.08 209.55 0)
      (effects (font (size 1.27 1.27) (thickness 0.15)) (justify left bottom) hide)
    )
    (property "Footprint" "antmicro-footprints:R_0402_1005Metric" (at 132.08 212.09 0)
      (effects (font (size 1.27 1.27) (thickness 0.15)) (justify left bottom) hide)
    )
    (property "Datasheet" "https://www.bourns.com/docs/product-datasheets/cr.pdf" (at 132.08 214.63 0)
      (effects (font (size 1.27 1.27) (thickness 0.15)) (justify left bottom) hide)
    )
    (property "MPN" "CR0402-FX-1402GLF" (at 132.08 217.17 0)
      (effects (font (size 1.27 1.27) (thickness 0.15)) (justify left bottom) hide)
    )
    (property "Manufacturer" "Bourns" (at 132.08 219.71 0)
      (effects (font (size 1.27 1.27) (thickness 0.15)) (justify left bottom) hide)
    )
    (property "License" "Apache-2.0" (at 132.08 222.25 0)
      (effects (font (size 1.27 1.27) (thickness 0.15)) (justify left bottom) hide)
    )
    (property "Val" "14k" (at 119.38 195.58 0)
      (effects (font (size 1.27 1.27) (thickness 0.15)))
    )
    (property "Tolerance" "1%" (at 132.08 207.01 0)
      (effects (font (size 1.27 1.27)) (justify left bottom) hide)
    )
    (property "Author" "Antmicro" (at 132.08 224.79 0)
      (effects (font (size 1.27 1.27) (thickness 0.15)) (justify left bottom) hide)
    )
    (pin "1")
    (pin "2")
    (instances
      (project "thunderbolt-pcie-adapter"
        (path ""
          (reference "R76") (unit 1)
        )
      )
    )
  )

  (symbol (lib_id "antmicroCapacitors0402:C_10p_0402") (at 392.43 151.13 0) (unit 1)
    (in_bom yes) (on_board yes) (dnp no)
    (property "Reference" "C116" (at 394.97 148.59 0)
      (effects (font (size 1.27 1.27) (thickness 0.15)))
    )
    (property "Value" "C_10p_0402" (at 412.75 161.29 0)
      (effects (font (size 1.27 1.27) (thickness 0.15)) (justify left bottom) hide)
    )
    (property "Footprint" "antmicro-footprints:C_0402_1005Metric" (at 412.75 163.83 0)
      (effects (font (size 1.27 1.27) (thickness 0.15)) (justify left bottom) hide)
    )
    (property "Datasheet" "https://www.murata.com/products/productdetail?partno=GCM1555C1H100GA16%23" (at 412.75 166.37 0)
      (effects (font (size 1.27 1.27) (thickness 0.15)) (justify left bottom) hide)
    )
    (property "MPN" "GCM1555C1H100GA16D" (at 412.75 168.91 0)
      (effects (font (size 1.27 1.27) (thickness 0.15)) (justify left bottom) hide)
    )
    (property "Manufacturer" "Murata" (at 412.75 171.45 0)
      (effects (font (size 1.27 1.27) (thickness 0.15)) (justify left bottom) hide)
    )
    (property "License" "Apache-2.0" (at 412.75 173.99 0)
      (effects (font (size 1.27 1.27) (thickness 0.15)) (justify left bottom) hide)
    )
    (property "Val" "10p" (at 393.065 154.94 0)
      (effects (font (size 1.27 1.27) (thickness 0.15)) (justify left bottom))
    )
    (property "Voltage" "50V" (at 412.75 179.07 0)
      (effects (font (size 1.27 1.27)) (justify left bottom) hide)
    )
    (property "Dielectric" "C0G" (at 412.75 181.61 0)
      (effects (font (size 1.27 1.27)) (justify left bottom) hide)
    )
    (property "Author" "Antmicro" (at 412.75 176.53 0)
      (effects (font (size 1.27 1.27) (thickness 0.15)) (justify left bottom) hide)
    )
    (pin "1")
    (pin "2")
    (instances
      (project "thunderbolt-pcie-adapter"
        (path ""
          (reference "C116") (unit 1)
        )
      )
    )
  )

  (symbol (lib_id "antmicroResistors0402:R_499R_0402") (at 68.58 96.52 0) (unit 1)
    (in_bom yes) (on_board yes) (dnp no)
    (property "Reference" "R68" (at 71.12 94.615 0)
      (effects (font (size 1.27 1.27) (thickness 0.15)))
    )
    (property "Value" "R_499R_0402" (at 88.9 109.22 0)
      (effects (font (size 1.27 1.27) (thickness 0.15)) (justify left bottom) hide)
    )
    (property "Footprint" "antmicro-footprints:R_0402_1005Metric" (at 88.9 111.76 0)
      (effects (font (size 1.27 1.27) (thickness 0.15)) (justify left bottom) hide)
    )
    (property "Datasheet" "https://www.mouser.com/datasheet/2/54/cr-1858361.pdf" (at 88.9 114.3 0)
      (effects (font (size 1.27 1.27) (thickness 0.15)) (justify left bottom) hide)
    )
    (property "MPN" "CR0402-FX-4990GLF" (at 88.9 116.84 0)
      (effects (font (size 1.27 1.27) (thickness 0.15)) (justify left bottom) hide)
    )
    (property "Manufacturer" "Bourns" (at 88.9 119.38 0)
      (effects (font (size 1.27 1.27) (thickness 0.15)) (justify left bottom) hide)
    )
    (property "License" "Apache-2.0" (at 88.9 121.92 0)
      (effects (font (size 1.27 1.27) (thickness 0.15)) (justify left bottom) hide)
    )
    (property "Val" "499R" (at 68.58 99.695 0)
      (effects (font (size 1.27 1.27) (thickness 0.15)) (justify left bottom))
    )
    (property "Tolerance" "1%" (at 88.9 106.68 0)
      (effects (font (size 1.27 1.27)) (justify left bottom) hide)
    )
    (property "Author" "Antmicro" (at 88.9 124.46 0)
      (effects (font (size 1.27 1.27) (thickness 0.15)) (justify left bottom) hide)
    )
    (pin "1")
    (pin "2")
    (instances
      (project "thunderbolt-pcie-adapter"
        (path ""
          (reference "R68") (unit 1)
        )
      )
    )
  )

  (symbol (lib_id "antmicroCapacitors0402:C_220n_0402") (at 265.43 46.99 0) (unit 1)
    (in_bom yes) (on_board yes) (dnp no)
    (property "Reference" "C109" (at 264.795 45.72 0)
      (effects (font (size 1.27 1.27) (thickness 0.15)))
    )
    (property "Value" "C_220n_0402" (at 285.75 57.15 0)
      (effects (font (size 1.27 1.27) (thickness 0.15)) (justify left bottom) hide)
    )
    (property "Footprint" "antmicro-footprints:C_0402_1005Metric" (at 285.75 59.69 0)
      (effects (font (size 1.27 1.27) (thickness 0.15)) (justify left bottom) hide)
    )
    (property "Datasheet" "https://www.yageo.com/en/Chart/Download/pdf/CC0402KRX5R6BB224" (at 285.75 62.23 0)
      (effects (font (size 1.27 1.27) (thickness 0.15)) (justify left bottom) hide)
    )
    (property "MPN" "CC0402KRX5R6BB224" (at 285.75 64.77 0)
      (effects (font (size 1.27 1.27) (thickness 0.15)) (justify left bottom) hide)
    )
    (property "Manufacturer" "YAGEO" (at 285.75 67.31 0)
      (effects (font (size 1.27 1.27) (thickness 0.15)) (justify left bottom) hide)
    )
    (property "License" "Apache-2.0" (at 285.75 69.85 0)
      (effects (font (size 1.27 1.27) (thickness 0.15)) (justify left bottom) hide)
    )
    (property "Val" "220n" (at 269.24 46.355 0)
      (effects (font (size 1.27 1.27) (thickness 0.15)) (justify left bottom))
    )
    (property "Voltage" "" (at 285.75 74.93 0)
      (effects (font (size 1.27 1.27)) (justify left bottom) hide)
    )
    (property "Dielectric" "" (at 285.75 77.47 0)
      (effects (font (size 1.27 1.27)) (justify left bottom) hide)
    )
    (property "Author" "Antmicro" (at 285.75 72.39 0)
      (effects (font (size 1.27 1.27) (thickness 0.15)) (justify left bottom) hide)
    )
    (pin "1")
    (pin "2")
    (instances
      (project "thunderbolt-pcie-adapter"
        (path ""
          (reference "C109") (unit 1)
        )
      )
    )
  )

  (symbol (lib_id "antmicroResistors0402:R_3k3_0402") (at 313.69 224.79 90) (unit 1)
    (in_bom yes) (on_board yes) (dnp no)
    (property "Reference" "R52" (at 314.96 220.98 90)
      (effects (font (size 1.27 1.27) (thickness 0.15)) (justify right))
    )
    (property "Value" "R_3k3_0402" (at 326.39 204.47 0)
      (effects (font (size 1.27 1.27) (thickness 0.15)) (justify left bottom) hide)
    )
    (property "Footprint" "antmicro-footprints:R_0402_1005Metric" (at 328.93 204.47 0)
      (effects (font (size 1.27 1.27) (thickness 0.15)) (justify left bottom) hide)
    )
    (property "Datasheet" "https://www.bourns.com/docs/product-datasheets/cr.pdf" (at 331.47 204.47 0)
      (effects (font (size 1.27 1.27) (thickness 0.15)) (justify left bottom) hide)
    )
    (property "MPN" "CR0402-FX-3301GLF" (at 334.01 204.47 0)
      (effects (font (size 1.27 1.27) (thickness 0.15)) (justify left bottom) hide)
    )
    (property "Manufacturer" "Bourns" (at 336.55 204.47 0)
      (effects (font (size 1.27 1.27) (thickness 0.15)) (justify left bottom) hide)
    )
    (property "License" "Apache-2.0" (at 339.09 204.47 0)
      (effects (font (size 1.27 1.27) (thickness 0.15)) (justify left bottom) hide)
    )
    (property "Val" "3k3" (at 318.77 222.25 90)
      (effects (font (size 1.27 1.27) (thickness 0.15)) (justify left bottom))
    )
    (property "Tolerance" "1%" (at 323.85 204.47 0)
      (effects (font (size 1.27 1.27)) (justify left bottom) hide)
    )
    (property "Author" "Antmicro" (at 341.63 204.47 0)
      (effects (font (size 1.27 1.27) (thickness 0.15)) (justify left bottom) hide)
    )
    (pin "1")
    (pin "2")
    (instances
      (project "thunderbolt-pcie-adapter"
        (path ""
          (reference "R52") (unit 1)
        )
      )
    )
  )

  (symbol (lib_id "antmicroResistors0402:R_100k_0402") (at 111.76 247.65 0) (unit 1)
    (in_bom yes) (on_board yes) (dnp no)
    (property "Reference" "R87" (at 110.49 246.38 0)
      (effects (font (size 1.27 1.27) (thickness 0.15)))
    )
    (property "Value" "R_100k_0402" (at 132.08 260.35 0)
      (effects (font (size 1.27 1.27) (thickness 0.15)) (justify left bottom) hide)
    )
    (property "Footprint" "antmicro-footprints:R_0402_1005Metric" (at 132.08 262.89 0)
      (effects (font (size 1.27 1.27) (thickness 0.15)) (justify left bottom) hide)
    )
    (property "Datasheet" "https://www.bourns.com/docs/product-datasheets/cr.pdf" (at 132.08 265.43 0)
      (effects (font (size 1.27 1.27) (thickness 0.15)) (justify left bottom) hide)
    )
    (property "MPN" "CR0402-FX-1003GLF" (at 132.08 267.97 0)
      (effects (font (size 1.27 1.27) (thickness 0.15)) (justify left bottom) hide)
    )
    (property "Manufacturer" "Bourns" (at 132.08 270.51 0)
      (effects (font (size 1.27 1.27) (thickness 0.15)) (justify left bottom) hide)
    )
    (property "License" "Apache-2.0" (at 132.08 273.05 0)
      (effects (font (size 1.27 1.27) (thickness 0.15)) (justify left bottom) hide)
    )
    (property "Val" "100k" (at 116.84 247.015 0)
      (effects (font (size 1.27 1.27) (thickness 0.15)) (justify left bottom))
    )
    (property "Tolerance" "1%" (at 132.08 257.81 0)
      (effects (font (size 1.27 1.27)) (justify left bottom) hide)
    )
    (property "Author" "Antmicro" (at 132.08 275.59 0)
      (effects (font (size 1.27 1.27) (thickness 0.15)) (justify left bottom) hide)
    )
    (pin "1")
    (pin "2")
    (instances
      (project "thunderbolt-pcie-adapter"
        (path ""
          (reference "R87") (unit 1)
        )
      )
    )
  )

  (symbol (lib_id "antmicroResistors0402:R_3k3_0402") (at 322.58 237.49 180) (unit 1)
    (in_bom yes) (on_board yes) (dnp no)
    (property "Reference" "R53" (at 313.69 236.22 0)
      (effects (font (size 1.27 1.27) (thickness 0.15)) (justify right))
    )
    (property "Value" "R_3k3_0402" (at 302.26 224.79 0)
      (effects (font (size 1.27 1.27) (thickness 0.15)) (justify left bottom) hide)
    )
    (property "Footprint" "antmicro-footprints:R_0402_1005Metric" (at 302.26 222.25 0)
      (effects (font (size 1.27 1.27) (thickness 0.15)) (justify left bottom) hide)
    )
    (property "Datasheet" "https://www.bourns.com/docs/product-datasheets/cr.pdf" (at 302.26 219.71 0)
      (effects (font (size 1.27 1.27) (thickness 0.15)) (justify left bottom) hide)
    )
    (property "MPN" "CR0402-FX-3301GLF" (at 302.26 217.17 0)
      (effects (font (size 1.27 1.27) (thickness 0.15)) (justify left bottom) hide)
    )
    (property "Manufacturer" "Bourns" (at 302.26 214.63 0)
      (effects (font (size 1.27 1.27) (thickness 0.15)) (justify left bottom) hide)
    )
    (property "License" "Apache-2.0" (at 302.26 212.09 0)
      (effects (font (size 1.27 1.27) (thickness 0.15)) (justify left bottom) hide)
    )
    (property "Val" "3k3" (at 325.755 235.585 0)
      (effects (font (size 1.27 1.27) (thickness 0.15)) (justify left bottom))
    )
    (property "Tolerance" "1%" (at 302.26 227.33 0)
      (effects (font (size 1.27 1.27)) (justify left bottom) hide)
    )
    (property "Author" "Antmicro" (at 302.26 209.55 0)
      (effects (font (size 1.27 1.27) (thickness 0.15)) (justify left bottom) hide)
    )
    (pin "1")
    (pin "2")
    (instances
      (project "thunderbolt-pcie-adapter"
        (path ""
          (reference "R53") (unit 1)
        )
      )
    )
  )

  (symbol (lib_id "antmicroInterfaceControllers:JHL6340SLLSQ") (at 180.34 144.78 0) (unit 6)
    (in_bom yes) (on_board yes) (dnp no) (fields_autoplaced)
    (property "Reference" "U4" (at 208.28 135.89 0)
      (effects (font (size 1.27 1.27) (thickness 0.15)))
    )
    (property "Value" "JHL6340SLLSQ" (at 251.46 147.32 0)
      (effects (font (size 1.27 1.27) (thickness 0.15)) (justify left bottom) hide)
    )
    (property "Footprint" "antmicro-footprints:JHL6340SLLSQ" (at 251.46 149.86 0)
      (effects (font (size 1.27 1.27) (thickness 0.15)) (justify left bottom) hide)
    )
    (property "Datasheet" "https://www.thunderbolttechnology.net/sites/default/files/18-241_ThunderboltController_Brief_HI.pdf" (at 251.46 152.4 0)
      (effects (font (size 1.27 1.27) (thickness 0.15)) (justify left bottom) hide)
    )
    (property "Manufacturer" "Intel" (at 251.46 154.94 0)
      (effects (font (size 1.27 1.27) (thickness 0.15)) (justify left bottom) hide)
    )
    (property "MPN" "JHL6340SLLSQ" (at 208.28 138.43 0)
      (effects (font (size 1.27 1.27) (thickness 0.15)))
    )
    (property "Author" "Antmicro" (at 251.46 160.02 0)
      (effects (font (size 1.27 1.27) (thickness 0.15)) (justify left bottom) hide)
    )
    (property "License" "Apache-2.0" (at 251.46 162.56 0)
      (effects (font (size 1.27 1.27) (thickness 0.15)) (justify left bottom) hide)
    )
    (pin "A1")
    (pin "A10")
    (pin "A12")
    (pin "A14")
    (pin "A16")
    (pin "A18")
    (pin "A2")
    (pin "A20")
    (pin "A22")
    (pin "A3")
    (pin "A6")
    (pin "A8")
    (pin "AA22")
    (pin "AA23")
    (pin "AB1")
    (pin "AB10")
    (pin "AB12")
    (pin "AB14")
    (pin "AB16")
    (pin "AB18")
    (pin "AB20")
    (pin "AB22")
    (pin "AB6")
    (pin "AB8")
    (pin "AC10")
    (pin "AC12")
    (pin "AC14")
    (pin "AC16")
    (pin "AC18")
    (pin "AC2")
    (pin "AC20")
    (pin "AC22")
    (pin "AC6")
    (pin "AC8")
    (pin "B1")
    (pin "B10")
    (pin "B12")
    (pin "B14")
    (pin "B16")
    (pin "B18")
    (pin "B2")
    (pin "B20")
    (pin "B22")
    (pin "B3")
    (pin "B6")
    (pin "B8")
    (pin "C1")
    (pin "C2")
    (pin "D1")
    (pin "D11")
    (pin "D12")
    (pin "D13")
    (pin "D15")
    (pin "D16")
    (pin "D18")
    (pin "D5")
    (pin "D8")
    (pin "D9")
    (pin "E11")
    (pin "E12")
    (pin "E13")
    (pin "E15")
    (pin "E16")
    (pin "E22")
    (pin "E23")
    (pin "E4")
    (pin "E5")
    (pin "E6")
    (pin "E8")
    (pin "E9")
    (pin "F11")
    (pin "F12")
    (pin "F13")
    (pin "F15")
    (pin "F16")
    (pin "F18")
    (pin "F20")
    (pin "F5")
    (pin "F6")
    (pin "F8")
    (pin "F9")
    (pin "G22")
    (pin "G23")
    (pin "H1")
    (pin "H11")
    (pin "H12")
    (pin "H13")
    (pin "H15")
    (pin "H16")
    (pin "H18")
    (pin "H2")
    (pin "H20")
    (pin "H5")
    (pin "H8")
    (pin "H9")
    (pin "J11")
    (pin "J12")
    (pin "J13")
    (pin "J15")
    (pin "J16")
    (pin "J18")
    (pin "J19")
    (pin "J20")
    (pin "J22")
    (pin "J23")
    (pin "J5")
    (pin "J8")
    (pin "J9")
    (pin "K1")
    (pin "K2")
    (pin "L11")
    (pin "L12")
    (pin "L13")
    (pin "L16")
    (pin "L18")
    (pin "L19")
    (pin "L20")
    (pin "L22")
    (pin "L23")
    (pin "L5")
    (pin "L6")
    (pin "L8")
    (pin "L9")
    (pin "M1")
    (pin "M11")
    (pin "M12")
    (pin "M13")
    (pin "M15")
    (pin "M16")
    (pin "M18")
    (pin "M19")
    (pin "M2")
    (pin "M20")
    (pin "M5")
    (pin "M6")
    (pin "M8")
    (pin "M9")
    (pin "N11")
    (pin "N12")
    (pin "N13")
    (pin "N18")
    (pin "N19")
    (pin "N20")
    (pin "N22")
    (pin "N23")
    (pin "N5")
    (pin "N8")
    (pin "N9")
    (pin "P1")
    (pin "P2")
    (pin "R11")
    (pin "R12")
    (pin "R13")
    (pin "R15")
    (pin "R16")
    (pin "R18")
    (pin "R19")
    (pin "R20")
    (pin "R22")
    (pin "R23")
    (pin "R5")
    (pin "R6")
    (pin "R8")
    (pin "R9")
    (pin "T1")
    (pin "T11")
    (pin "T12")
    (pin "T13")
    (pin "T15")
    (pin "T16")
    (pin "T18")
    (pin "T2")
    (pin "T20")
    (pin "T5")
    (pin "T6")
    (pin "T8")
    (pin "T9")
    (pin "U22")
    (pin "U23")
    (pin "V11")
    (pin "V12")
    (pin "V13")
    (pin "V15")
    (pin "V16")
    (pin "V20")
    (pin "V5")
    (pin "V6")
    (pin "V8")
    (pin "V9")
    (pin "W20")
    (pin "W22")
    (pin "W23")
    (pin "W5")
    (pin "W6")
    (pin "W8")
    (pin "W9")
    (pin "Y13")
    (pin "Y20")
    (pin "Y9")
    (pin "AC5")
    (pin "F22")
    (pin "F23")
    (pin "H22")
    (pin "H23")
    (pin "K22")
    (pin "K23")
    (pin "L4")
    (pin "M22")
    (pin "M23")
    (pin "N16")
    (pin "P22")
    (pin "P23")
    (pin "T19")
    (pin "T22")
    (pin "T23")
    (pin "V19")
    (pin "V22")
    (pin "V23")
    (pin "Y22")
    (pin "Y23")
    (pin "AA1")
    (pin "AA2")
    (pin "AB11")
    (pin "AB13")
    (pin "AB15")
    (pin "AB17")
    (pin "AB19")
    (pin "AB21")
    (pin "AB7")
    (pin "AB9")
    (pin "AC11")
    (pin "AC13")
    (pin "AC15")
    (pin "AC17")
    (pin "AC19")
    (pin "AC21")
    (pin "AC7")
    (pin "AC9")
    (pin "D2")
    (pin "D4")
    (pin "E2")
    (pin "F1")
    (pin "F2")
    (pin "G1")
    (pin "H4")
    (pin "J1")
    (pin "J2")
    (pin "J4")
    (pin "L1")
    (pin "L2")
    (pin "N1")
    (pin "N2")
    (pin "N4")
    (pin "N6")
    (pin "R1")
    (pin "R2")
    (pin "R4")
    (pin "U1")
    (pin "U2")
    (pin "V1")
    (pin "V2")
    (pin "W1")
    (pin "W11")
    (pin "W12")
    (pin "W19")
    (pin "W2")
    (pin "Y1")
    (pin "Y11")
    (pin "Y12")
    (pin "Y18")
    (pin "Y19")
    (pin "Y2")
    (pin "Y5")
    (pin "Y6")
    (pin "Y8")
    (pin "AB3")
    (pin "AB4")
    (pin "AB5")
    (pin "AC3")
    (pin "AC4")
    (pin "D22")
    (pin "D23")
    (pin "E1")
    (pin "F4")
    (pin "H6")
    (pin "J6")
    (pin "T4")
    (pin "V4")
    (pin "W4")
    (pin "Y4")
    (pin "A11")
    (pin "A13")
    (pin "A15")
    (pin "A17")
    (pin "A19")
    (pin "A21")
    (pin "A4")
    (pin "A5")
    (pin "A7")
    (pin "A9")
    (pin "B11")
    (pin "B13")
    (pin "B15")
    (pin "B17")
    (pin "B19")
    (pin "B21")
    (pin "B4")
    (pin "B5")
    (pin "B7")
    (pin "B9")
    (pin "D19")
    (pin "D20")
    (pin "E19")
    (pin "E20")
    (pin "F19")
    (pin "G2")
    (pin "H19")
    (pin "M4")
    (pin "W15")
    (pin "W16")
    (pin "Y15")
    (pin "Y16")
    (pin "A23")
    (pin "AB2")
    (pin "AB23")
    (pin "AC1")
    (pin "AC23")
    (pin "B23")
    (pin "C22")
    (pin "C23")
    (pin "D6")
    (pin "E18")
    (pin "L15")
    (pin "N15")
    (pin "V18")
    (pin "W13")
    (pin "W18")
    (instances
      (project "thunderbolt-pcie-adapter"
        (path ""
          (reference "U4") (unit 6)
        )
      )
    )
  )

  (symbol (lib_id "antmicroResistors0402:R_14k_0402") (at 43.18 257.81 0) (unit 1)
    (in_bom yes) (on_board yes) (dnp yes)
    (property "Reference" "R63" (at 41.275 256.54 0)
      (effects (font (size 1.27 1.27) (thickness 0.15)))
    )
    (property "Value" "R_14k_0402" (at 63.5 270.51 0)
      (effects (font (size 1.27 1.27) (thickness 0.15)) (justify left bottom) hide)
    )
    (property "Footprint" "antmicro-footprints:R_0402_1005Metric" (at 63.5 273.05 0)
      (effects (font (size 1.27 1.27) (thickness 0.15)) (justify left bottom) hide)
    )
    (property "Datasheet" "https://www.bourns.com/docs/product-datasheets/cr.pdf" (at 63.5 275.59 0)
      (effects (font (size 1.27 1.27) (thickness 0.15)) (justify left bottom) hide)
    )
    (property "MPN" "CR0402-FX-1402GLF" (at 63.5 278.13 0)
      (effects (font (size 1.27 1.27) (thickness 0.15)) (justify left bottom) hide)
    )
    (property "Manufacturer" "Bourns" (at 63.5 280.67 0)
      (effects (font (size 1.27 1.27) (thickness 0.15)) (justify left bottom) hide)
    )
    (property "License" "Apache-2.0" (at 63.5 283.21 0)
      (effects (font (size 1.27 1.27) (thickness 0.15)) (justify left bottom) hide)
    )
    (property "Val" "14k" (at 50.165 256.54 0)
      (effects (font (size 1.27 1.27) (thickness 0.15)))
    )
    (property "Tolerance" "1%" (at 63.5 267.97 0)
      (effects (font (size 1.27 1.27)) (justify left bottom) hide)
    )
    (property "Author" "Antmicro" (at 63.5 285.75 0)
      (effects (font (size 1.27 1.27) (thickness 0.15)) (justify left bottom) hide)
    )
    (pin "1")
    (pin "2")
    (instances
      (project "thunderbolt-pcie-adapter"
        (path ""
          (reference "R63") (unit 1)
        )
      )
    )
  )

  (symbol (lib_id "antmicroInterfaceControllers:JHL6340SLLSQ") (at 181.61 46.99 0) (unit 2)
    (in_bom yes) (on_board yes) (dnp no) (fields_autoplaced)
    (property "Reference" "U4" (at 209.55 37.465 0)
      (effects (font (size 1.27 1.27) (thickness 0.15)))
    )
    (property "Value" "JHL6340SLLSQ" (at 252.73 49.53 0)
      (effects (font (size 1.27 1.27) (thickness 0.15)) (justify left bottom) hide)
    )
    (property "Footprint" "antmicro-footprints:JHL6340SLLSQ" (at 252.73 52.07 0)
      (effects (font (size 1.27 1.27) (thickness 0.15)) (justify left bottom) hide)
    )
    (property "Datasheet" "https://www.thunderbolttechnology.net/sites/default/files/18-241_ThunderboltController_Brief_HI.pdf" (at 252.73 54.61 0)
      (effects (font (size 1.27 1.27) (thickness 0.15)) (justify left bottom) hide)
    )
    (property "Manufacturer" "Intel" (at 252.73 57.15 0)
      (effects (font (size 1.27 1.27) (thickness 0.15)) (justify left bottom) hide)
    )
    (property "MPN" "JHL6340SLLSQ" (at 209.55 40.005 0)
      (effects (font (size 1.27 1.27) (thickness 0.15)))
    )
    (property "Author" "Antmicro" (at 252.73 62.23 0)
      (effects (font (size 1.27 1.27) (thickness 0.15)) (justify left bottom) hide)
    )
    (property "License" "Apache-2.0" (at 252.73 64.77 0)
      (effects (font (size 1.27 1.27) (thickness 0.15)) (justify left bottom) hide)
    )
    (pin "A1")
    (pin "A10")
    (pin "A12")
    (pin "A14")
    (pin "A16")
    (pin "A18")
    (pin "A2")
    (pin "A20")
    (pin "A22")
    (pin "A3")
    (pin "A6")
    (pin "A8")
    (pin "AA22")
    (pin "AA23")
    (pin "AB1")
    (pin "AB10")
    (pin "AB12")
    (pin "AB14")
    (pin "AB16")
    (pin "AB18")
    (pin "AB20")
    (pin "AB22")
    (pin "AB6")
    (pin "AB8")
    (pin "AC10")
    (pin "AC12")
    (pin "AC14")
    (pin "AC16")
    (pin "AC18")
    (pin "AC2")
    (pin "AC20")
    (pin "AC22")
    (pin "AC6")
    (pin "AC8")
    (pin "B1")
    (pin "B10")
    (pin "B12")
    (pin "B14")
    (pin "B16")
    (pin "B18")
    (pin "B2")
    (pin "B20")
    (pin "B22")
    (pin "B3")
    (pin "B6")
    (pin "B8")
    (pin "C1")
    (pin "C2")
    (pin "D1")
    (pin "D11")
    (pin "D12")
    (pin "D13")
    (pin "D15")
    (pin "D16")
    (pin "D18")
    (pin "D5")
    (pin "D8")
    (pin "D9")
    (pin "E11")
    (pin "E12")
    (pin "E13")
    (pin "E15")
    (pin "E16")
    (pin "E22")
    (pin "E23")
    (pin "E4")
    (pin "E5")
    (pin "E6")
    (pin "E8")
    (pin "E9")
    (pin "F11")
    (pin "F12")
    (pin "F13")
    (pin "F15")
    (pin "F16")
    (pin "F18")
    (pin "F20")
    (pin "F5")
    (pin "F6")
    (pin "F8")
    (pin "F9")
    (pin "G22")
    (pin "G23")
    (pin "H1")
    (pin "H11")
    (pin "H12")
    (pin "H13")
    (pin "H15")
    (pin "H16")
    (pin "H18")
    (pin "H2")
    (pin "H20")
    (pin "H5")
    (pin "H8")
    (pin "H9")
    (pin "J11")
    (pin "J12")
    (pin "J13")
    (pin "J15")
    (pin "J16")
    (pin "J18")
    (pin "J19")
    (pin "J20")
    (pin "J22")
    (pin "J23")
    (pin "J5")
    (pin "J8")
    (pin "J9")
    (pin "K1")
    (pin "K2")
    (pin "L11")
    (pin "L12")
    (pin "L13")
    (pin "L16")
    (pin "L18")
    (pin "L19")
    (pin "L20")
    (pin "L22")
    (pin "L23")
    (pin "L5")
    (pin "L6")
    (pin "L8")
    (pin "L9")
    (pin "M1")
    (pin "M11")
    (pin "M12")
    (pin "M13")
    (pin "M15")
    (pin "M16")
    (pin "M18")
    (pin "M19")
    (pin "M2")
    (pin "M20")
    (pin "M5")
    (pin "M6")
    (pin "M8")
    (pin "M9")
    (pin "N11")
    (pin "N12")
    (pin "N13")
    (pin "N18")
    (pin "N19")
    (pin "N20")
    (pin "N22")
    (pin "N23")
    (pin "N5")
    (pin "N8")
    (pin "N9")
    (pin "P1")
    (pin "P2")
    (pin "R11")
    (pin "R12")
    (pin "R13")
    (pin "R15")
    (pin "R16")
    (pin "R18")
    (pin "R19")
    (pin "R20")
    (pin "R22")
    (pin "R23")
    (pin "R5")
    (pin "R6")
    (pin "R8")
    (pin "R9")
    (pin "T1")
    (pin "T11")
    (pin "T12")
    (pin "T13")
    (pin "T15")
    (pin "T16")
    (pin "T18")
    (pin "T2")
    (pin "T20")
    (pin "T5")
    (pin "T6")
    (pin "T8")
    (pin "T9")
    (pin "U22")
    (pin "U23")
    (pin "V11")
    (pin "V12")
    (pin "V13")
    (pin "V15")
    (pin "V16")
    (pin "V20")
    (pin "V5")
    (pin "V6")
    (pin "V8")
    (pin "V9")
    (pin "W20")
    (pin "W22")
    (pin "W23")
    (pin "W5")
    (pin "W6")
    (pin "W8")
    (pin "W9")
    (pin "Y13")
    (pin "Y20")
    (pin "Y9")
    (pin "AC5")
    (pin "F22")
    (pin "F23")
    (pin "H22")
    (pin "H23")
    (pin "K22")
    (pin "K23")
    (pin "L4")
    (pin "M22")
    (pin "M23")
    (pin "N16")
    (pin "P22")
    (pin "P23")
    (pin "T19")
    (pin "T22")
    (pin "T23")
    (pin "V19")
    (pin "V22")
    (pin "V23")
    (pin "Y22")
    (pin "Y23")
    (pin "AA1")
    (pin "AA2")
    (pin "AB11")
    (pin "AB13")
    (pin "AB15")
    (pin "AB17")
    (pin "AB19")
    (pin "AB21")
    (pin "AB7")
    (pin "AB9")
    (pin "AC11")
    (pin "AC13")
    (pin "AC15")
    (pin "AC17")
    (pin "AC19")
    (pin "AC21")
    (pin "AC7")
    (pin "AC9")
    (pin "D2")
    (pin "D4")
    (pin "E2")
    (pin "F1")
    (pin "F2")
    (pin "G1")
    (pin "H4")
    (pin "J1")
    (pin "J2")
    (pin "J4")
    (pin "L1")
    (pin "L2")
    (pin "N1")
    (pin "N2")
    (pin "N4")
    (pin "N6")
    (pin "R1")
    (pin "R2")
    (pin "R4")
    (pin "U1")
    (pin "U2")
    (pin "V1")
    (pin "V2")
    (pin "W1")
    (pin "W11")
    (pin "W12")
    (pin "W19")
    (pin "W2")
    (pin "Y1")
    (pin "Y11")
    (pin "Y12")
    (pin "Y18")
    (pin "Y19")
    (pin "Y2")
    (pin "Y5")
    (pin "Y6")
    (pin "Y8")
    (pin "AB3")
    (pin "AB4")
    (pin "AB5")
    (pin "AC3")
    (pin "AC4")
    (pin "D22")
    (pin "D23")
    (pin "E1")
    (pin "F4")
    (pin "H6")
    (pin "J6")
    (pin "T4")
    (pin "V4")
    (pin "W4")
    (pin "Y4")
    (pin "A11")
    (pin "A13")
    (pin "A15")
    (pin "A17")
    (pin "A19")
    (pin "A21")
    (pin "A4")
    (pin "A5")
    (pin "A7")
    (pin "A9")
    (pin "B11")
    (pin "B13")
    (pin "B15")
    (pin "B17")
    (pin "B19")
    (pin "B21")
    (pin "B4")
    (pin "B5")
    (pin "B7")
    (pin "B9")
    (pin "D19")
    (pin "D20")
    (pin "E19")
    (pin "E20")
    (pin "F19")
    (pin "G2")
    (pin "H19")
    (pin "M4")
    (pin "W15")
    (pin "W16")
    (pin "Y15")
    (pin "Y16")
    (pin "A23")
    (pin "AB2")
    (pin "AB23")
    (pin "AC1")
    (pin "AC23")
    (pin "B23")
    (pin "C22")
    (pin "C23")
    (pin "D6")
    (pin "E18")
    (pin "L15")
    (pin "N15")
    (pin "V18")
    (pin "W13")
    (pin "W18")
    (instances
      (project "thunderbolt-pcie-adapter"
        (path ""
          (reference "U4") (unit 2)
        )
      )
    )
  )

  (symbol (lib_id "antmicroResistors0402:R_10k_0402") (at 293.37 144.78 0) (unit 1)
    (in_bom yes) (on_board yes) (dnp no)
    (property "Reference" "R64" (at 291.465 143.51 0)
      (effects (font (size 1.27 1.27) (thickness 0.15)))
    )
    (property "Value" "R_10k_0402" (at 313.69 157.48 0)
      (effects (font (size 1.27 1.27) (thickness 0.15)) (justify left bottom) hide)
    )
    (property "Footprint" "antmicro-footprints:R_0402_1005Metric" (at 313.69 160.02 0)
      (effects (font (size 1.27 1.27) (thickness 0.15)) (justify left bottom) hide)
    )
    (property "Datasheet" "https://www.bourns.com/docs/product-datasheets/cr.pdf" (at 313.69 162.56 0)
      (effects (font (size 1.27 1.27) (thickness 0.15)) (justify left bottom) hide)
    )
    (property "MPN" "CR0402-FX-1002GLF" (at 313.69 165.1 0)
      (effects (font (size 1.27 1.27) (thickness 0.15)) (justify left bottom) hide)
    )
    (property "Manufacturer" "Bourns" (at 313.69 167.64 0)
      (effects (font (size 1.27 1.27) (thickness 0.15)) (justify left bottom) hide)
    )
    (property "License" "Apache-2.0" (at 313.69 170.18 0)
      (effects (font (size 1.27 1.27) (thickness 0.15)) (justify left bottom) hide)
    )
    (property "Val" "10k" (at 298.45 144.145 0)
      (effects (font (size 1.27 1.27) (thickness 0.15)) (justify left bottom))
    )
    (property "Tolerance" "1%" (at 313.69 154.94 0)
      (effects (font (size 1.27 1.27)) (justify left bottom) hide)
    )
    (property "Author" "Antmicro" (at 313.69 172.72 0)
      (effects (font (size 1.27 1.27) (thickness 0.15)) (justify left bottom) hide)
    )
    (pin "1")
    (pin "2")
    (instances
      (project "thunderbolt-pcie-adapter"
        (path ""
          (reference "R64") (unit 1)
        )
      )
    )
  )

  (symbol (lib_id "antmicroResistors0402:R_1M_0402") (at 111.76 224.79 0) (unit 1)
    (in_bom yes) (on_board yes) (dnp no)
    (property "Reference" "R82" (at 110.49 223.52 0)
      (effects (font (size 1.27 1.27) (thickness 0.15)))
    )
    (property "Value" "R_1M_0402" (at 132.08 237.49 0)
      (effects (font (size 1.27 1.27) (thickness 0.15)) (justify left bottom) hide)
    )
    (property "Footprint" "antmicro-footprints:R_0402_1005Metric" (at 132.08 240.03 0)
      (effects (font (size 1.27 1.27) (thickness 0.15)) (justify left bottom) hide)
    )
    (property "Datasheet" "https://www.bourns.com/docs/product-datasheets/cr.pdf" (at 132.08 242.57 0)
      (effects (font (size 1.27 1.27) (thickness 0.15)) (justify left bottom) hide)
    )
    (property "MPN" "CR0402-FX-1004GLF" (at 132.08 245.11 0)
      (effects (font (size 1.27 1.27) (thickness 0.15)) (justify left bottom) hide)
    )
    (property "Manufacturer" "Bourns" (at 132.08 247.65 0)
      (effects (font (size 1.27 1.27) (thickness 0.15)) (justify left bottom) hide)
    )
    (property "License" "Apache-2.0" (at 132.08 250.19 0)
      (effects (font (size 1.27 1.27) (thickness 0.15)) (justify left bottom) hide)
    )
    (property "Val" "1M" (at 116.205 224.155 0)
      (effects (font (size 1.27 1.27) (thickness 0.15)) (justify left bottom))
    )
    (property "Tolerance" "1%" (at 132.08 234.95 0)
      (effects (font (size 1.27 1.27)) (justify left bottom) hide)
    )
    (property "Author" "Antmicro" (at 132.08 252.73 0)
      (effects (font (size 1.27 1.27) (thickness 0.15)) (justify left bottom) hide)
    )
    (pin "1")
    (pin "2")
    (instances
      (project "thunderbolt-pcie-adapter"
        (path ""
          (reference "R82") (unit 1)
        )
      )
    )
  )

  (symbol (lib_id "antmicropower:GND") (at 123.19 226.06 0) (unit 1)
    (in_bom yes) (on_board yes) (dnp no)
    (property "Reference" "#PWR0143" (at 123.19 232.41 0)
      (effects (font (size 1.27 1.27)) hide)
    )
    (property "Value" "GND" (at 121.92 230.505 0)
      (effects (font (size 1.27 1.27) (thickness 0.15)) (justify left bottom))
    )
    (property "Footprint" "" (at 123.19 226.06 0)
      (effects (font (size 1.27 1.27) (thickness 0.15)) (justify left bottom) hide)
    )
    (property "Datasheet" "" (at 123.19 226.06 0)
      (effects (font (size 1.27 1.27) (thickness 0.15)) (justify left bottom) hide)
    )
    (property "Author" "Antmicro" (at 132.08 233.68 0)
      (effects (font (size 1.27 1.27) (thickness 0.15)) (justify left bottom) hide)
    )
    (property "License" "Apache-2.0" (at 132.08 236.22 0)
      (effects (font (size 1.27 1.27) (thickness 0.15)) (justify left bottom) hide)
    )
    (pin "1")
    (instances
      (project "thunderbolt-pcie-adapter"
        (path ""
          (reference "#PWR0143") (unit 1)
        )
      )
    )
  )

  (symbol (lib_id "antmicroCapacitors0402:C_220n_0402") (at 259.08 72.39 0) (unit 1)
    (in_bom yes) (on_board yes) (dnp no)
    (property "Reference" "C108" (at 252.095 71.12 0)
      (effects (font (size 1.27 1.27) (thickness 0.15)))
    )
    (property "Value" "C_220n_0402" (at 279.4 82.55 0)
      (effects (font (size 1.27 1.27) (thickness 0.15)) (justify left bottom) hide)
    )
    (property "Footprint" "antmicro-footprints:C_0402_1005Metric" (at 279.4 85.09 0)
      (effects (font (size 1.27 1.27) (thickness 0.15)) (justify left bottom) hide)
    )
    (property "Datasheet" "https://www.yageo.com/en/Chart/Download/pdf/CC0402KRX5R6BB224" (at 279.4 87.63 0)
      (effects (font (size 1.27 1.27) (thickness 0.15)) (justify left bottom) hide)
    )
    (property "MPN" "CC0402KRX5R6BB224" (at 279.4 90.17 0)
      (effects (font (size 1.27 1.27) (thickness 0.15)) (justify left bottom) hide)
    )
    (property "Manufacturer" "YAGEO" (at 279.4 92.71 0)
      (effects (font (size 1.27 1.27) (thickness 0.15)) (justify left bottom) hide)
    )
    (property "License" "Apache-2.0" (at 279.4 95.25 0)
      (effects (font (size 1.27 1.27) (thickness 0.15)) (justify left bottom) hide)
    )
    (property "Val" "220n" (at 255.27 71.755 0)
      (effects (font (size 1.27 1.27) (thickness 0.15)) (justify left bottom))
    )
    (property "Voltage" "" (at 279.4 100.33 0)
      (effects (font (size 1.27 1.27)) (justify left bottom) hide)
    )
    (property "Dielectric" "" (at 279.4 102.87 0)
      (effects (font (size 1.27 1.27)) (justify left bottom) hide)
    )
    (property "Author" "Antmicro" (at 279.4 97.79 0)
      (effects (font (size 1.27 1.27) (thickness 0.15)) (justify left bottom) hide)
    )
    (pin "1")
    (pin "2")
    (instances
      (project "thunderbolt-pcie-adapter"
        (path ""
          (reference "C108") (unit 1)
        )
      )
    )
  )

  (symbol (lib_id "antmicroCapacitors0402:C_220n_0402") (at 259.08 64.77 0) (unit 1)
    (in_bom yes) (on_board yes) (dnp no)
    (property "Reference" "C107" (at 252.095 63.5 0)
      (effects (font (size 1.27 1.27) (thickness 0.15)))
    )
    (property "Value" "C_220n_0402" (at 279.4 74.93 0)
      (effects (font (size 1.27 1.27) (thickness 0.15)) (justify left bottom) hide)
    )
    (property "Footprint" "antmicro-footprints:C_0402_1005Metric" (at 279.4 77.47 0)
      (effects (font (size 1.27 1.27) (thickness 0.15)) (justify left bottom) hide)
    )
    (property "Datasheet" "https://www.yageo.com/en/Chart/Download/pdf/CC0402KRX5R6BB224" (at 279.4 80.01 0)
      (effects (font (size 1.27 1.27) (thickness 0.15)) (justify left bottom) hide)
    )
    (property "MPN" "CC0402KRX5R6BB224" (at 279.4 82.55 0)
      (effects (font (size 1.27 1.27) (thickness 0.15)) (justify left bottom) hide)
    )
    (property "Manufacturer" "YAGEO" (at 279.4 85.09 0)
      (effects (font (size 1.27 1.27) (thickness 0.15)) (justify left bottom) hide)
    )
    (property "License" "Apache-2.0" (at 279.4 87.63 0)
      (effects (font (size 1.27 1.27) (thickness 0.15)) (justify left bottom) hide)
    )
    (property "Val" "220n" (at 255.27 64.135 0)
      (effects (font (size 1.27 1.27) (thickness 0.15)) (justify left bottom))
    )
    (property "Voltage" "" (at 279.4 92.71 0)
      (effects (font (size 1.27 1.27)) (justify left bottom) hide)
    )
    (property "Dielectric" "" (at 279.4 95.25 0)
      (effects (font (size 1.27 1.27)) (justify left bottom) hide)
    )
    (property "Author" "Antmicro" (at 279.4 90.17 0)
      (effects (font (size 1.27 1.27) (thickness 0.15)) (justify left bottom) hide)
    )
    (pin "1")
    (pin "2")
    (instances
      (project "thunderbolt-pcie-adapter"
        (path ""
          (reference "C107") (unit 1)
        )
      )
    )
  )

  (symbol (lib_id "antmicroCapacitors0402:C_220n_0402") (at 265.43 62.23 0) (unit 1)
    (in_bom yes) (on_board yes) (dnp no)
    (property "Reference" "C111" (at 264.795 60.96 0)
      (effects (font (size 1.27 1.27) (thickness 0.15)))
    )
    (property "Value" "C_220n_0402" (at 285.75 72.39 0)
      (effects (font (size 1.27 1.27) (thickness 0.15)) (justify left bottom) hide)
    )
    (property "Footprint" "antmicro-footprints:C_0402_1005Metric" (at 285.75 74.93 0)
      (effects (font (size 1.27 1.27) (thickness 0.15)) (justify left bottom) hide)
    )
    (property "Datasheet" "https://www.yageo.com/en/Chart/Download/pdf/CC0402KRX5R6BB224" (at 285.75 77.47 0)
      (effects (font (size 1.27 1.27) (thickness 0.15)) (justify left bottom) hide)
    )
    (property "MPN" "CC0402KRX5R6BB224" (at 285.75 80.01 0)
      (effects (font (size 1.27 1.27) (thickness 0.15)) (justify left bottom) hide)
    )
    (property "Manufacturer" "YAGEO" (at 285.75 82.55 0)
      (effects (font (size 1.27 1.27) (thickness 0.15)) (justify left bottom) hide)
    )
    (property "License" "Apache-2.0" (at 285.75 85.09 0)
      (effects (font (size 1.27 1.27) (thickness 0.15)) (justify left bottom) hide)
    )
    (property "Val" "220n" (at 269.24 61.595 0)
      (effects (font (size 1.27 1.27) (thickness 0.15)) (justify left bottom))
    )
    (property "Voltage" "" (at 285.75 90.17 0)
      (effects (font (size 1.27 1.27)) (justify left bottom) hide)
    )
    (property "Dielectric" "" (at 285.75 92.71 0)
      (effects (font (size 1.27 1.27)) (justify left bottom) hide)
    )
    (property "Author" "Antmicro" (at 285.75 87.63 0)
      (effects (font (size 1.27 1.27) (thickness 0.15)) (justify left bottom) hide)
    )
    (pin "1")
    (pin "2")
    (instances
      (project "thunderbolt-pcie-adapter"
        (path ""
          (reference "C111") (unit 1)
        )
      )
    )
  )

  (symbol (lib_id "antmicropower:GND") (at 311.15 54.61 270) (unit 1)
    (in_bom yes) (on_board yes) (dnp no)
    (property "Reference" "#PWR0141" (at 304.8 54.61 0)
      (effects (font (size 1.27 1.27)) hide)
    )
    (property "Value" "GND" (at 306.705 52.705 0)
      (effects (font (size 1.27 1.27) (thickness 0.15)) (justify left bottom))
    )
    (property "Footprint" "" (at 311.15 54.61 0)
      (effects (font (size 1.27 1.27) (thickness 0.15)) (justify left bottom) hide)
    )
    (property "Datasheet" "" (at 311.15 54.61 0)
      (effects (font (size 1.27 1.27) (thickness 0.15)) (justify left bottom) hide)
    )
    (property "Author" "Antmicro" (at 303.53 63.5 0)
      (effects (font (size 1.27 1.27) (thickness 0.15)) (justify left bottom) hide)
    )
    (property "License" "Apache-2.0" (at 300.99 63.5 0)
      (effects (font (size 1.27 1.27) (thickness 0.15)) (justify left bottom) hide)
    )
    (pin "1")
    (instances
      (project "thunderbolt-pcie-adapter"
        (path ""
          (reference "#PWR0141") (unit 1)
        )
      )
    )
  )

  (symbol (lib_id "antmicropower:GND") (at 340.36 60.96 0) (unit 1)
    (in_bom yes) (on_board yes) (dnp no)
    (property "Reference" "#PWR0148" (at 340.36 67.31 0)
      (effects (font (size 1.27 1.27)) hide)
    )
    (property "Value" "GND" (at 338.455 65.405 0)
      (effects (font (size 1.27 1.27) (thickness 0.15)) (justify left bottom))
    )
    (property "Footprint" "" (at 340.36 60.96 0)
      (effects (font (size 1.27 1.27) (thickness 0.15)) (justify left bottom) hide)
    )
    (property "Datasheet" "" (at 340.36 60.96 0)
      (effects (font (size 1.27 1.27) (thickness 0.15)) (justify left bottom) hide)
    )
    (property "Author" "Antmicro" (at 349.25 68.58 0)
      (effects (font (size 1.27 1.27) (thickness 0.15)) (justify left bottom) hide)
    )
    (property "License" "Apache-2.0" (at 349.25 71.12 0)
      (effects (font (size 1.27 1.27) (thickness 0.15)) (justify left bottom) hide)
    )
    (pin "1")
    (instances
      (project "thunderbolt-pcie-adapter"
        (path ""
          (reference "#PWR0148") (unit 1)
        )
      )
    )
  )

  (symbol (lib_id "antmicroResistors0402:R_100k_0402") (at 111.76 212.09 0) (unit 1)
    (in_bom yes) (on_board yes) (dnp no)
    (property "Reference" "R77" (at 110.49 210.82 0)
      (effects (font (size 1.27 1.27) (thickness 0.15)))
    )
    (property "Value" "R_100k_0402" (at 132.08 224.79 0)
      (effects (font (size 1.27 1.27) (thickness 0.15)) (justify left bottom) hide)
    )
    (property "Footprint" "antmicro-footprints:R_0402_1005Metric" (at 132.08 227.33 0)
      (effects (font (size 1.27 1.27) (thickness 0.15)) (justify left bottom) hide)
    )
    (property "Datasheet" "https://www.bourns.com/docs/product-datasheets/cr.pdf" (at 132.08 229.87 0)
      (effects (font (size 1.27 1.27) (thickness 0.15)) (justify left bottom) hide)
    )
    (property "MPN" "CR0402-FX-1003GLF" (at 132.08 232.41 0)
      (effects (font (size 1.27 1.27) (thickness 0.15)) (justify left bottom) hide)
    )
    (property "Manufacturer" "Bourns" (at 132.08 234.95 0)
      (effects (font (size 1.27 1.27) (thickness 0.15)) (justify left bottom) hide)
    )
    (property "License" "Apache-2.0" (at 132.08 237.49 0)
      (effects (font (size 1.27 1.27) (thickness 0.15)) (justify left bottom) hide)
    )
    (property "Val" "100k" (at 116.205 211.455 0)
      (effects (font (size 1.27 1.27) (thickness 0.15)) (justify left bottom))
    )
    (property "Tolerance" "1%" (at 132.08 222.25 0)
      (effects (font (size 1.27 1.27)) (justify left bottom) hide)
    )
    (property "Author" "Antmicro" (at 132.08 240.03 0)
      (effects (font (size 1.27 1.27) (thickness 0.15)) (justify left bottom) hide)
    )
    (pin "1")
    (pin "2")
    (instances
      (project "thunderbolt-pcie-adapter"
        (path ""
          (reference "R77") (unit 1)
        )
      )
    )
  )

  (symbol (lib_id "antmicropower:GND") (at 232.41 219.71 0) (unit 1)
    (in_bom yes) (on_board yes) (dnp no)
    (property "Reference" "#PWR0129" (at 232.41 226.06 0)
      (effects (font (size 1.27 1.27)) hide)
    )
    (property "Value" "GND" (at 230.505 224.79 0)
      (effects (font (size 1.27 1.27) (thickness 0.15)) (justify left bottom))
    )
    (property "Footprint" "" (at 232.41 219.71 0)
      (effects (font (size 1.27 1.27) (thickness 0.15)) (justify left bottom) hide)
    )
    (property "Datasheet" "" (at 232.41 219.71 0)
      (effects (font (size 1.27 1.27) (thickness 0.15)) (justify left bottom) hide)
    )
    (property "Author" "Antmicro" (at 241.3 227.33 0)
      (effects (font (size 1.27 1.27) (thickness 0.15)) (justify left bottom) hide)
    )
    (property "License" "Apache-2.0" (at 241.3 229.87 0)
      (effects (font (size 1.27 1.27) (thickness 0.15)) (justify left bottom) hide)
    )
    (pin "1")
    (instances
      (project "thunderbolt-pcie-adapter"
        (path ""
          (reference "#PWR0129") (unit 1)
        )
      )
    )
  )

  (symbol (lib_id "antmicroInterfaceControllers:JHL6340SLLSQ") (at 302.26 144.78 0) (unit 4)
    (in_bom yes) (on_board yes) (dnp no) (fields_autoplaced)
    (property "Reference" "U4" (at 330.2 135.89 0)
      (effects (font (size 1.27 1.27) (thickness 0.15)))
    )
    (property "Value" "JHL6340SLLSQ" (at 373.38 147.32 0)
      (effects (font (size 1.27 1.27) (thickness 0.15)) (justify left bottom) hide)
    )
    (property "Footprint" "antmicro-footprints:JHL6340SLLSQ" (at 373.38 149.86 0)
      (effects (font (size 1.27 1.27) (thickness 0.15)) (justify left bottom) hide)
    )
    (property "Datasheet" "https://www.thunderbolttechnology.net/sites/default/files/18-241_ThunderboltController_Brief_HI.pdf" (at 373.38 152.4 0)
      (effects (font (size 1.27 1.27) (thickness 0.15)) (justify left bottom) hide)
    )
    (property "Manufacturer" "Intel" (at 373.38 154.94 0)
      (effects (font (size 1.27 1.27) (thickness 0.15)) (justify left bottom) hide)
    )
    (property "MPN" "JHL6340SLLSQ" (at 330.2 138.43 0)
      (effects (font (size 1.27 1.27) (thickness 0.15)))
    )
    (property "Author" "Antmicro" (at 373.38 160.02 0)
      (effects (font (size 1.27 1.27) (thickness 0.15)) (justify left bottom) hide)
    )
    (property "License" "Apache-2.0" (at 373.38 162.56 0)
      (effects (font (size 1.27 1.27) (thickness 0.15)) (justify left bottom) hide)
    )
    (pin "A1")
    (pin "A10")
    (pin "A12")
    (pin "A14")
    (pin "A16")
    (pin "A18")
    (pin "A2")
    (pin "A20")
    (pin "A22")
    (pin "A3")
    (pin "A6")
    (pin "A8")
    (pin "AA22")
    (pin "AA23")
    (pin "AB1")
    (pin "AB10")
    (pin "AB12")
    (pin "AB14")
    (pin "AB16")
    (pin "AB18")
    (pin "AB20")
    (pin "AB22")
    (pin "AB6")
    (pin "AB8")
    (pin "AC10")
    (pin "AC12")
    (pin "AC14")
    (pin "AC16")
    (pin "AC18")
    (pin "AC2")
    (pin "AC20")
    (pin "AC22")
    (pin "AC6")
    (pin "AC8")
    (pin "B1")
    (pin "B10")
    (pin "B12")
    (pin "B14")
    (pin "B16")
    (pin "B18")
    (pin "B2")
    (pin "B20")
    (pin "B22")
    (pin "B3")
    (pin "B6")
    (pin "B8")
    (pin "C1")
    (pin "C2")
    (pin "D1")
    (pin "D11")
    (pin "D12")
    (pin "D13")
    (pin "D15")
    (pin "D16")
    (pin "D18")
    (pin "D5")
    (pin "D8")
    (pin "D9")
    (pin "E11")
    (pin "E12")
    (pin "E13")
    (pin "E15")
    (pin "E16")
    (pin "E22")
    (pin "E23")
    (pin "E4")
    (pin "E5")
    (pin "E6")
    (pin "E8")
    (pin "E9")
    (pin "F11")
    (pin "F12")
    (pin "F13")
    (pin "F15")
    (pin "F16")
    (pin "F18")
    (pin "F20")
    (pin "F5")
    (pin "F6")
    (pin "F8")
    (pin "F9")
    (pin "G22")
    (pin "G23")
    (pin "H1")
    (pin "H11")
    (pin "H12")
    (pin "H13")
    (pin "H15")
    (pin "H16")
    (pin "H18")
    (pin "H2")
    (pin "H20")
    (pin "H5")
    (pin "H8")
    (pin "H9")
    (pin "J11")
    (pin "J12")
    (pin "J13")
    (pin "J15")
    (pin "J16")
    (pin "J18")
    (pin "J19")
    (pin "J20")
    (pin "J22")
    (pin "J23")
    (pin "J5")
    (pin "J8")
    (pin "J9")
    (pin "K1")
    (pin "K2")
    (pin "L11")
    (pin "L12")
    (pin "L13")
    (pin "L16")
    (pin "L18")
    (pin "L19")
    (pin "L20")
    (pin "L22")
    (pin "L23")
    (pin "L5")
    (pin "L6")
    (pin "L8")
    (pin "L9")
    (pin "M1")
    (pin "M11")
    (pin "M12")
    (pin "M13")
    (pin "M15")
    (pin "M16")
    (pin "M18")
    (pin "M19")
    (pin "M2")
    (pin "M20")
    (pin "M5")
    (pin "M6")
    (pin "M8")
    (pin "M9")
    (pin "N11")
    (pin "N12")
    (pin "N13")
    (pin "N18")
    (pin "N19")
    (pin "N20")
    (pin "N22")
    (pin "N23")
    (pin "N5")
    (pin "N8")
    (pin "N9")
    (pin "P1")
    (pin "P2")
    (pin "R11")
    (pin "R12")
    (pin "R13")
    (pin "R15")
    (pin "R16")
    (pin "R18")
    (pin "R19")
    (pin "R20")
    (pin "R22")
    (pin "R23")
    (pin "R5")
    (pin "R6")
    (pin "R8")
    (pin "R9")
    (pin "T1")
    (pin "T11")
    (pin "T12")
    (pin "T13")
    (pin "T15")
    (pin "T16")
    (pin "T18")
    (pin "T2")
    (pin "T20")
    (pin "T5")
    (pin "T6")
    (pin "T8")
    (pin "T9")
    (pin "U22")
    (pin "U23")
    (pin "V11")
    (pin "V12")
    (pin "V13")
    (pin "V15")
    (pin "V16")
    (pin "V20")
    (pin "V5")
    (pin "V6")
    (pin "V8")
    (pin "V9")
    (pin "W20")
    (pin "W22")
    (pin "W23")
    (pin "W5")
    (pin "W6")
    (pin "W8")
    (pin "W9")
    (pin "Y13")
    (pin "Y20")
    (pin "Y9")
    (pin "AC5")
    (pin "F22")
    (pin "F23")
    (pin "H22")
    (pin "H23")
    (pin "K22")
    (pin "K23")
    (pin "L4")
    (pin "M22")
    (pin "M23")
    (pin "N16")
    (pin "P22")
    (pin "P23")
    (pin "T19")
    (pin "T22")
    (pin "T23")
    (pin "V19")
    (pin "V22")
    (pin "V23")
    (pin "Y22")
    (pin "Y23")
    (pin "AA1")
    (pin "AA2")
    (pin "AB11")
    (pin "AB13")
    (pin "AB15")
    (pin "AB17")
    (pin "AB19")
    (pin "AB21")
    (pin "AB7")
    (pin "AB9")
    (pin "AC11")
    (pin "AC13")
    (pin "AC15")
    (pin "AC17")
    (pin "AC19")
    (pin "AC21")
    (pin "AC7")
    (pin "AC9")
    (pin "D2")
    (pin "D4")
    (pin "E2")
    (pin "F1")
    (pin "F2")
    (pin "G1")
    (pin "H4")
    (pin "J1")
    (pin "J2")
    (pin "J4")
    (pin "L1")
    (pin "L2")
    (pin "N1")
    (pin "N2")
    (pin "N4")
    (pin "N6")
    (pin "R1")
    (pin "R2")
    (pin "R4")
    (pin "U1")
    (pin "U2")
    (pin "V1")
    (pin "V2")
    (pin "W1")
    (pin "W11")
    (pin "W12")
    (pin "W19")
    (pin "W2")
    (pin "Y1")
    (pin "Y11")
    (pin "Y12")
    (pin "Y18")
    (pin "Y19")
    (pin "Y2")
    (pin "Y5")
    (pin "Y6")
    (pin "Y8")
    (pin "AB3")
    (pin "AB4")
    (pin "AB5")
    (pin "AC3")
    (pin "AC4")
    (pin "D22")
    (pin "D23")
    (pin "E1")
    (pin "F4")
    (pin "H6")
    (pin "J6")
    (pin "T4")
    (pin "V4")
    (pin "W4")
    (pin "Y4")
    (pin "A11")
    (pin "A13")
    (pin "A15")
    (pin "A17")
    (pin "A19")
    (pin "A21")
    (pin "A4")
    (pin "A5")
    (pin "A7")
    (pin "A9")
    (pin "B11")
    (pin "B13")
    (pin "B15")
    (pin "B17")
    (pin "B19")
    (pin "B21")
    (pin "B4")
    (pin "B5")
    (pin "B7")
    (pin "B9")
    (pin "D19")
    (pin "D20")
    (pin "E19")
    (pin "E20")
    (pin "F19")
    (pin "G2")
    (pin "H19")
    (pin "M4")
    (pin "W15")
    (pin "W16")
    (pin "Y15")
    (pin "Y16")
    (pin "A23")
    (pin "AB2")
    (pin "AB23")
    (pin "AC1")
    (pin "AC23")
    (pin "B23")
    (pin "C22")
    (pin "C23")
    (pin "D6")
    (pin "E18")
    (pin "L15")
    (pin "N15")
    (pin "V18")
    (pin "W13")
    (pin "W18")
    (instances
      (project "thunderbolt-pcie-adapter"
        (path ""
          (reference "U4") (unit 4)
        )
      )
    )
  )

  (symbol (lib_id "antmicroResistors0402:R_100k_0402") (at 111.76 191.77 0) (unit 1)
    (in_bom yes) (on_board yes) (dnp no)
    (property "Reference" "R75" (at 109.22 190.5 0)
      (effects (font (size 1.27 1.27) (thickness 0.15)))
    )
    (property "Value" "R_100k_0402" (at 132.08 204.47 0)
      (effects (font (size 1.27 1.27) (thickness 0.15)) (justify left bottom) hide)
    )
    (property "Footprint" "antmicro-footprints:R_0402_1005Metric" (at 132.08 207.01 0)
      (effects (font (size 1.27 1.27) (thickness 0.15)) (justify left bottom) hide)
    )
    (property "Datasheet" "https://www.bourns.com/docs/product-datasheets/cr.pdf" (at 132.08 209.55 0)
      (effects (font (size 1.27 1.27) (thickness 0.15)) (justify left bottom) hide)
    )
    (property "MPN" "CR0402-FX-1003GLF" (at 132.08 212.09 0)
      (effects (font (size 1.27 1.27) (thickness 0.15)) (justify left bottom) hide)
    )
    (property "Manufacturer" "Bourns" (at 132.08 214.63 0)
      (effects (font (size 1.27 1.27) (thickness 0.15)) (justify left bottom) hide)
    )
    (property "License" "Apache-2.0" (at 132.08 217.17 0)
      (effects (font (size 1.27 1.27) (thickness 0.15)) (justify left bottom) hide)
    )
    (property "Val" "100k" (at 116.84 191.135 0)
      (effects (font (size 1.27 1.27) (thickness 0.15)) (justify left bottom))
    )
    (property "Tolerance" "1%" (at 132.08 201.93 0)
      (effects (font (size 1.27 1.27)) (justify left bottom) hide)
    )
    (property "Author" "Antmicro" (at 132.08 219.71 0)
      (effects (font (size 1.27 1.27) (thickness 0.15)) (justify left bottom) hide)
    )
    (pin "1")
    (pin "2")
    (instances
      (project "thunderbolt-pcie-adapter"
        (path ""
          (reference "R75") (unit 1)
        )
      )
    )
  )

  (symbol (lib_id "antmicroResistors0402:R_10k_0402") (at 172.72 85.09 0) (unit 1)
    (in_bom yes) (on_board yes) (dnp no)
    (property "Reference" "R56" (at 175.26 83.185 0)
      (effects (font (size 1.27 1.27) (thickness 0.15)))
    )
    (property "Value" "R_10k_0402" (at 193.04 97.79 0)
      (effects (font (size 1.27 1.27) (thickness 0.15)) (justify left bottom) hide)
    )
    (property "Footprint" "antmicro-footprints:R_0402_1005Metric" (at 193.04 100.33 0)
      (effects (font (size 1.27 1.27) (thickness 0.15)) (justify left bottom) hide)
    )
    (property "Datasheet" "https://www.bourns.com/docs/product-datasheets/cr.pdf" (at 193.04 102.87 0)
      (effects (font (size 1.27 1.27) (thickness 0.15)) (justify left bottom) hide)
    )
    (property "MPN" "CR0402-FX-1002GLF" (at 193.04 105.41 0)
      (effects (font (size 1.27 1.27) (thickness 0.15)) (justify left bottom) hide)
    )
    (property "Manufacturer" "Bourns" (at 193.04 107.95 0)
      (effects (font (size 1.27 1.27) (thickness 0.15)) (justify left bottom) hide)
    )
    (property "License" "Apache-2.0" (at 193.04 110.49 0)
      (effects (font (size 1.27 1.27) (thickness 0.15)) (justify left bottom) hide)
    )
    (property "Val" "10k" (at 173.355 88.265 0)
      (effects (font (size 1.27 1.27) (thickness 0.15)) (justify left bottom))
    )
    (property "Tolerance" "1%" (at 193.04 95.25 0)
      (effects (font (size 1.27 1.27)) (justify left bottom) hide)
    )
    (property "Author" "Antmicro" (at 193.04 113.03 0)
      (effects (font (size 1.27 1.27) (thickness 0.15)) (justify left bottom) hide)
    )
    (pin "1")
    (pin "2")
    (instances
      (project "thunderbolt-pcie-adapter"
        (path ""
          (reference "R56") (unit 1)
        )
      )
    )
  )

  (symbol (lib_id "antmicroResistors0402:R_100k_0402") (at 43.18 245.11 0) (unit 1)
    (in_bom yes) (on_board yes) (dnp no)
    (property "Reference" "R60" (at 41.275 243.84 0)
      (effects (font (size 1.27 1.27) (thickness 0.15)))
    )
    (property "Value" "R_100k_0402" (at 63.5 257.81 0)
      (effects (font (size 1.27 1.27) (thickness 0.15)) (justify left bottom) hide)
    )
    (property "Footprint" "antmicro-footprints:R_0402_1005Metric" (at 63.5 260.35 0)
      (effects (font (size 1.27 1.27) (thickness 0.15)) (justify left bottom) hide)
    )
    (property "Datasheet" "https://www.bourns.com/docs/product-datasheets/cr.pdf" (at 63.5 262.89 0)
      (effects (font (size 1.27 1.27) (thickness 0.15)) (justify left bottom) hide)
    )
    (property "MPN" "CR0402-FX-1003GLF" (at 63.5 265.43 0)
      (effects (font (size 1.27 1.27) (thickness 0.15)) (justify left bottom) hide)
    )
    (property "Manufacturer" "Bourns" (at 63.5 267.97 0)
      (effects (font (size 1.27 1.27) (thickness 0.15)) (justify left bottom) hide)
    )
    (property "License" "Apache-2.0" (at 63.5 270.51 0)
      (effects (font (size 1.27 1.27) (thickness 0.15)) (justify left bottom) hide)
    )
    (property "Val" "100k" (at 47.625 244.475 0)
      (effects (font (size 1.27 1.27) (thickness 0.15)) (justify left bottom))
    )
    (property "Tolerance" "1%" (at 63.5 255.27 0)
      (effects (font (size 1.27 1.27)) (justify left bottom) hide)
    )
    (property "Author" "Antmicro" (at 63.5 273.05 0)
      (effects (font (size 1.27 1.27) (thickness 0.15)) (justify left bottom) hide)
    )
    (pin "1")
    (pin "2")
    (instances
      (project "thunderbolt-pcie-adapter"
        (path ""
          (reference "R60") (unit 1)
        )
      )
    )
  )

  (symbol (lib_id "antmicroResonators:Resonator_25MHz_ABM8G") (at 317.5 50.8 270) (unit 1)
    (in_bom yes) (on_board yes) (dnp no)
    (property "Reference" "Y1" (at 321.31 52.07 90)
      (effects (font (size 1.27 1.27) (thickness 0.15)) (justify left))
    )
    (property "Value" "Resonator_25MHz_ABM8G" (at 304.8 66.04 0)
      (effects (font (size 1.27 1.27) (thickness 0.15)) (justify left bottom) hide)
    )
    (property "Footprint" "antmicro-footprints:Resonator_SMD_Abracon_ABM8G_3.2x2.5mm" (at 302.26 66.04 0)
      (effects (font (size 1.27 1.27) (thickness 0.15)) (justify left bottom) hide)
    )
    (property "Datasheet" "https://abracon.com/Resonators/ABM8G.pdf" (at 299.72 66.04 0)
      (effects (font (size 1.27 1.27) (thickness 0.15)) (justify left bottom) hide)
    )
    (property "MPN" "ABM8G-25.000MHZ-18-D2Y-T3" (at 302.26 66.675 90)
      (effects (font (size 1.27 1.27) (thickness 0.15)) (justify left) hide)
    )
    (property "Manufacturer" "Abracon" (at 297.18 66.04 0)
      (effects (font (size 1.27 1.27) (thickness 0.15)) (justify left bottom) hide)
    )
    (property "Author" "Antmicro" (at 294.64 66.04 0)
      (effects (font (size 1.27 1.27) (thickness 0.15)) (justify left bottom) hide)
    )
    (property "License" "Apache-2.0" (at 292.1 66.04 0)
      (effects (font (size 1.27 1.27) (thickness 0.15)) (justify left bottom) hide)
    )
    (property "Val" "25 MHz" (at 321.31 57.15 90)
      (effects (font (size 1.27 1.27) (thickness 0.15)) (justify left))
    )
    (pin "1")
    (pin "2")
    (pin "3")
    (pin "4")
    (instances
      (project "thunderbolt-pcie-adapter"
        (path ""
          (reference "Y1") (unit 1)
        )
      )
    )
  )

  (symbol (lib_id "antmicroCapacitors0402:C_100n_0402") (at 335.28 45.72 90) (unit 1)
    (in_bom yes) (on_board yes) (dnp no)
    (property "Reference" "C115" (at 328.295 41.91 90)
      (effects (font (size 1.27 1.27) (thickness 0.15)) (justify right))
    )
    (property "Value" "C_100n_0402" (at 345.44 25.4 0)
      (effects (font (size 1.27 1.27) (thickness 0.15)) (justify left bottom) hide)
    )
    (property "Footprint" "antmicro-footprints:C_0402_1005Metric" (at 347.98 25.4 0)
      (effects (font (size 1.27 1.27) (thickness 0.15)) (justify left bottom) hide)
    )
    (property "Datasheet" "https://www.murata.com/products/productdetail?partno=GRM155R61H104KE14%23" (at 350.52 25.4 0)
      (effects (font (size 1.27 1.27) (thickness 0.15)) (justify left bottom) hide)
    )
    (property "MPN" "GRM155R61H104KE14D" (at 353.06 25.4 0)
      (effects (font (size 1.27 1.27) (thickness 0.15)) (justify left bottom) hide)
    )
    (property "Manufacturer" "Murata" (at 355.6 25.4 0)
      (effects (font (size 1.27 1.27) (thickness 0.15)) (justify left bottom) hide)
    )
    (property "License" "Apache-2.0" (at 358.14 25.4 0)
      (effects (font (size 1.27 1.27) (thickness 0.15)) (justify left bottom) hide)
    )
    (property "Val" "100n" (at 333.375 44.45 90)
      (effects (font (size 1.27 1.27) (thickness 0.15)) (justify left bottom))
    )
    (property "Voltage" "50V" (at 363.22 25.4 0)
      (effects (font (size 1.27 1.27)) (justify left bottom) hide)
    )
    (property "Dielectric" "X5R" (at 365.76 25.4 0)
      (effects (font (size 1.27 1.27)) (justify left bottom) hide)
    )
    (property "Author" "Antmicro" (at 360.68 25.4 0)
      (effects (font (size 1.27 1.27) (thickness 0.15)) (justify left bottom) hide)
    )
    (pin "1")
    (pin "2")
    (instances
      (project "thunderbolt-pcie-adapter"
        (path ""
          (reference "C115") (unit 1)
        )
      )
    )
  )

  (symbol (lib_id "antmicroResistors0402:R_100k_0402") (at 111.76 245.11 0) (unit 1)
    (in_bom yes) (on_board yes) (dnp no)
    (property "Reference" "R86" (at 110.49 243.84 0)
      (effects (font (size 1.27 1.27) (thickness 0.15)))
    )
    (property "Value" "R_100k_0402" (at 132.08 257.81 0)
      (effects (font (size 1.27 1.27) (thickness 0.15)) (justify left bottom) hide)
    )
    (property "Footprint" "antmicro-footprints:R_0402_1005Metric" (at 132.08 260.35 0)
      (effects (font (size 1.27 1.27) (thickness 0.15)) (justify left bottom) hide)
    )
    (property "Datasheet" "https://www.bourns.com/docs/product-datasheets/cr.pdf" (at 132.08 262.89 0)
      (effects (font (size 1.27 1.27) (thickness 0.15)) (justify left bottom) hide)
    )
    (property "MPN" "CR0402-FX-1003GLF" (at 132.08 265.43 0)
      (effects (font (size 1.27 1.27) (thickness 0.15)) (justify left bottom) hide)
    )
    (property "Manufacturer" "Bourns" (at 132.08 267.97 0)
      (effects (font (size 1.27 1.27) (thickness 0.15)) (justify left bottom) hide)
    )
    (property "License" "Apache-2.0" (at 132.08 270.51 0)
      (effects (font (size 1.27 1.27) (thickness 0.15)) (justify left bottom) hide)
    )
    (property "Val" "100k" (at 116.84 244.475 0)
      (effects (font (size 1.27 1.27) (thickness 0.15)) (justify left bottom))
    )
    (property "Tolerance" "1%" (at 132.08 255.27 0)
      (effects (font (size 1.27 1.27)) (justify left bottom) hide)
    )
    (property "Author" "Antmicro" (at 132.08 273.05 0)
      (effects (font (size 1.27 1.27) (thickness 0.15)) (justify left bottom) hide)
    )
    (pin "1")
    (pin "2")
    (instances
      (project "thunderbolt-pcie-adapter"
        (path ""
          (reference "R86") (unit 1)
        )
      )
    )
  )

  (symbol (lib_id "antmicroResistors0402:R_100R_0402") (at 361.95 147.32 0) (unit 1)
    (in_bom yes) (on_board yes) (dnp no)
    (property "Reference" "R89" (at 360.68 146.05 0)
      (effects (font (size 1.27 1.27) (thickness 0.15)))
    )
    (property "Value" "R_100R_0402" (at 382.27 160.02 0)
      (effects (font (size 1.27 1.27) (thickness 0.15)) (justify left bottom) hide)
    )
    (property "Footprint" "antmicro-footprints:R_0402_1005Metric" (at 382.27 162.56 0)
      (effects (font (size 1.27 1.27) (thickness 0.15)) (justify left bottom) hide)
    )
    (property "Datasheet" "https://www.bourns.com/docs/product-datasheets/cr.pdf" (at 382.27 165.1 0)
      (effects (font (size 1.27 1.27) (thickness 0.15)) (justify left bottom) hide)
    )
    (property "MPN" "CR0402-FX-1000GLF" (at 382.27 167.64 0)
      (effects (font (size 1.27 1.27) (thickness 0.15)) (justify left bottom) hide)
    )
    (property "Manufacturer" "Bourns" (at 382.27 170.18 0)
      (effects (font (size 1.27 1.27) (thickness 0.15)) (justify left bottom) hide)
    )
    (property "License" "Apache-2.0" (at 382.27 172.72 0)
      (effects (font (size 1.27 1.27) (thickness 0.15)) (justify left bottom) hide)
    )
    (property "Val" "100R" (at 368.935 146.05 0)
      (effects (font (size 1.27 1.27) (thickness 0.15)))
    )
    (property "Tolerance" "1%" (at 382.27 157.48 0)
      (effects (font (size 1.27 1.27)) (justify left bottom) hide)
    )
    (property "Author" "Antmicro" (at 382.27 175.26 0)
      (effects (font (size 1.27 1.27) (thickness 0.15)) (justify left bottom) hide)
    )
    (pin "1")
    (pin "2")
    (instances
      (project "thunderbolt-pcie-adapter"
        (path ""
          (reference "R89") (unit 1)
        )
      )
    )
  )

  (symbol (lib_id "antmicropower:GND") (at 307.34 60.96 270) (unit 1)
    (in_bom yes) (on_board yes) (dnp no)
    (property "Reference" "#PWR0138" (at 300.99 60.96 0)
      (effects (font (size 1.27 1.27)) hide)
    )
    (property "Value" "GND" (at 302.895 59.055 0)
      (effects (font (size 1.27 1.27) (thickness 0.15)) (justify left bottom))
    )
    (property "Footprint" "" (at 307.34 60.96 0)
      (effects (font (size 1.27 1.27) (thickness 0.15)) (justify left bottom) hide)
    )
    (property "Datasheet" "" (at 307.34 60.96 0)
      (effects (font (size 1.27 1.27) (thickness 0.15)) (justify left bottom) hide)
    )
    (property "Author" "Antmicro" (at 299.72 69.85 0)
      (effects (font (size 1.27 1.27) (thickness 0.15)) (justify left bottom) hide)
    )
    (property "License" "Apache-2.0" (at 297.18 69.85 0)
      (effects (font (size 1.27 1.27) (thickness 0.15)) (justify left bottom) hide)
    )
    (pin "1")
    (instances
      (project "thunderbolt-pcie-adapter"
        (path ""
          (reference "#PWR0138") (unit 1)
        )
      )
    )
  )

  (symbol (lib_id "antmicroCapacitors0402:C_220n_0402") (at 265.43 54.61 0) (unit 1)
    (in_bom yes) (on_board yes) (dnp no)
    (property "Reference" "C110" (at 264.795 53.34 0)
      (effects (font (size 1.27 1.27) (thickness 0.15)))
    )
    (property "Value" "C_220n_0402" (at 285.75 64.77 0)
      (effects (font (size 1.27 1.27) (thickness 0.15)) (justify left bottom) hide)
    )
    (property "Footprint" "antmicro-footprints:C_0402_1005Metric" (at 285.75 67.31 0)
      (effects (font (size 1.27 1.27) (thickness 0.15)) (justify left bottom) hide)
    )
    (property "Datasheet" "https://www.yageo.com/en/Chart/Download/pdf/CC0402KRX5R6BB224" (at 285.75 69.85 0)
      (effects (font (size 1.27 1.27) (thickness 0.15)) (justify left bottom) hide)
    )
    (property "MPN" "CC0402KRX5R6BB224" (at 285.75 72.39 0)
      (effects (font (size 1.27 1.27) (thickness 0.15)) (justify left bottom) hide)
    )
    (property "Manufacturer" "YAGEO" (at 285.75 74.93 0)
      (effects (font (size 1.27 1.27) (thickness 0.15)) (justify left bottom) hide)
    )
    (property "License" "Apache-2.0" (at 285.75 77.47 0)
      (effects (font (size 1.27 1.27) (thickness 0.15)) (justify left bottom) hide)
    )
    (property "Val" "220n" (at 269.24 53.975 0)
      (effects (font (size 1.27 1.27) (thickness 0.15)) (justify left bottom))
    )
    (property "Voltage" "" (at 285.75 82.55 0)
      (effects (font (size 1.27 1.27)) (justify left bottom) hide)
    )
    (property "Dielectric" "" (at 285.75 85.09 0)
      (effects (font (size 1.27 1.27)) (justify left bottom) hide)
    )
    (property "Author" "Antmicro" (at 285.75 80.01 0)
      (effects (font (size 1.27 1.27) (thickness 0.15)) (justify left bottom) hide)
    )
    (pin "1")
    (pin "2")
    (instances
      (project "thunderbolt-pcie-adapter"
        (path ""
          (reference "C110") (unit 1)
        )
      )
    )
  )

  (symbol (lib_id "antmicropower:GND") (at 398.78 151.13 90) (unit 1)
    (in_bom yes) (on_board yes) (dnp no)
    (property "Reference" "#PWR0150" (at 405.13 151.13 0)
      (effects (font (size 1.27 1.27)) hide)
    )
    (property "Value" "GND" (at 403.225 153.035 0)
      (effects (font (size 1.27 1.27) (thickness 0.15)) (justify left bottom))
    )
    (property "Footprint" "" (at 398.78 151.13 0)
      (effects (font (size 1.27 1.27) (thickness 0.15)) (justify left bottom) hide)
    )
    (property "Datasheet" "" (at 398.78 151.13 0)
      (effects (font (size 1.27 1.27) (thickness 0.15)) (justify left bottom) hide)
    )
    (property "Author" "Antmicro" (at 406.4 142.24 0)
      (effects (font (size 1.27 1.27) (thickness 0.15)) (justify left bottom) hide)
    )
    (property "License" "Apache-2.0" (at 408.94 142.24 0)
      (effects (font (size 1.27 1.27) (thickness 0.15)) (justify left bottom) hide)
    )
    (pin "1")
    (instances
      (project "thunderbolt-pcie-adapter"
        (path ""
          (reference "#PWR0150") (unit 1)
        )
      )
    )
  )

  (symbol (lib_id "antmicroResistors0402:R_100R_0402") (at 361.95 144.78 0) (unit 1)
    (in_bom yes) (on_board yes) (dnp no)
    (property "Reference" "R88" (at 360.68 143.51 0)
      (effects (font (size 1.27 1.27) (thickness 0.15)))
    )
    (property "Value" "R_100R_0402" (at 382.27 157.48 0)
      (effects (font (size 1.27 1.27) (thickness 0.15)) (justify left bottom) hide)
    )
    (property "Footprint" "antmicro-footprints:R_0402_1005Metric" (at 382.27 160.02 0)
      (effects (font (size 1.27 1.27) (thickness 0.15)) (justify left bottom) hide)
    )
    (property "Datasheet" "https://www.bourns.com/docs/product-datasheets/cr.pdf" (at 382.27 162.56 0)
      (effects (font (size 1.27 1.27) (thickness 0.15)) (justify left bottom) hide)
    )
    (property "MPN" "CR0402-FX-1000GLF" (at 382.27 165.1 0)
      (effects (font (size 1.27 1.27) (thickness 0.15)) (justify left bottom) hide)
    )
    (property "Manufacturer" "Bourns" (at 382.27 167.64 0)
      (effects (font (size 1.27 1.27) (thickness 0.15)) (justify left bottom) hide)
    )
    (property "License" "Apache-2.0" (at 382.27 170.18 0)
      (effects (font (size 1.27 1.27) (thickness 0.15)) (justify left bottom) hide)
    )
    (property "Val" "100R" (at 368.935 143.51 0)
      (effects (font (size 1.27 1.27) (thickness 0.15)))
    )
    (property "Tolerance" "1%" (at 382.27 154.94 0)
      (effects (font (size 1.27 1.27)) (justify left bottom) hide)
    )
    (property "Author" "Antmicro" (at 382.27 172.72 0)
      (effects (font (size 1.27 1.27) (thickness 0.15)) (justify left bottom) hide)
    )
    (pin "1")
    (pin "2")
    (instances
      (project "thunderbolt-pcie-adapter"
        (path ""
          (reference "R88") (unit 1)
        )
      )
    )
  )

  (symbol (lib_id "antmicroResonators:Resonator_25MHz_ABM8G") (at 388.62 160.02 90) (unit 1)
    (in_bom yes) (on_board yes) (dnp no)
    (property "Reference" "Y2" (at 379.73 156.845 90)
      (effects (font (size 1.27 1.27) (thickness 0.15)) (justify left))
    )
    (property "Value" "Resonator_25MHz_ABM8G" (at 401.32 144.78 0)
      (effects (font (size 1.27 1.27) (thickness 0.15)) (justify left bottom) hide)
    )
    (property "Footprint" "antmicro-footprints:Resonator_SMD_Abracon_ABM8G_3.2x2.5mm" (at 403.86 144.78 0)
      (effects (font (size 1.27 1.27) (thickness 0.15)) (justify left bottom) hide)
    )
    (property "Datasheet" "https://abracon.com/Resonators/ABM8G.pdf" (at 406.4 144.78 0)
      (effects (font (size 1.27 1.27) (thickness 0.15)) (justify left bottom) hide)
    )
    (property "MPN" "ABM8G-25.000MHZ-18-D2Y-T3" (at 406.4 167.64 90)
      (effects (font (size 1.27 1.27) (thickness 0.15)) (justify left) hide)
    )
    (property "Manufacturer" "Abracon" (at 408.94 144.78 0)
      (effects (font (size 1.27 1.27) (thickness 0.15)) (justify left bottom) hide)
    )
    (property "Author" "Antmicro" (at 411.48 144.78 0)
      (effects (font (size 1.27 1.27) (thickness 0.15)) (justify left bottom) hide)
    )
    (property "License" "Apache-2.0" (at 414.02 144.78 0)
      (effects (font (size 1.27 1.27) (thickness 0.15)) (justify left bottom) hide)
    )
    (property "Val" "25 MHz" (at 384.81 158.75 90)
      (effects (font (size 1.27 1.27) (thickness 0.15)) (justify left))
    )
    (pin "1")
    (pin "2")
    (pin "3")
    (pin "4")
    (instances
      (project "thunderbolt-pcie-adapter"
        (path ""
          (reference "Y2") (unit 1)
        )
      )
    )
  )

  (symbol (lib_id "antmicroCapacitors0402:C_100n_0402") (at 50.8 73.66 0) (unit 1)
    (in_bom yes) (on_board yes) (dnp no)
    (property "Reference" "C104" (at 56.515 72.39 0)
      (effects (font (size 1.27 1.27) (thickness 0.15)))
    )
    (property "Value" "C_100n_0402" (at 71.12 83.82 0)
      (effects (font (size 1.27 1.27) (thickness 0.15)) (justify left bottom) hide)
    )
    (property "Footprint" "antmicro-footprints:C_0402_1005Metric" (at 71.12 86.36 0)
      (effects (font (size 1.27 1.27) (thickness 0.15)) (justify left bottom) hide)
    )
    (property "Datasheet" "https://www.murata.com/products/productdetail?partno=GRM155R61H104KE14%23" (at 71.12 88.9 0)
      (effects (font (size 1.27 1.27) (thickness 0.15)) (justify left bottom) hide)
    )
    (property "MPN" "GRM155R61H104KE14D" (at 71.12 91.44 0)
      (effects (font (size 1.27 1.27) (thickness 0.15)) (justify left bottom) hide)
    )
    (property "Manufacturer" "Murata" (at 71.12 93.98 0)
      (effects (font (size 1.27 1.27) (thickness 0.15)) (justify left bottom) hide)
    )
    (property "License" "Apache-2.0" (at 71.12 96.52 0)
      (effects (font (size 1.27 1.27) (thickness 0.15)) (justify left bottom) hide)
    )
    (property "Val" "100n" (at 59.055 73.025 0)
      (effects (font (size 1.27 1.27) (thickness 0.15)) (justify left bottom))
    )
    (property "Voltage" "50V" (at 71.12 101.6 0)
      (effects (font (size 1.27 1.27)) (justify left bottom) hide)
    )
    (property "Dielectric" "X5R" (at 71.12 104.14 0)
      (effects (font (size 1.27 1.27)) (justify left bottom) hide)
    )
    (property "Author" "Antmicro" (at 71.12 99.06 0)
      (effects (font (size 1.27 1.27) (thickness 0.15)) (justify left bottom) hide)
    )
    (pin "1")
    (pin "2")
    (instances
      (project "thunderbolt-pcie-adapter"
        (path ""
          (reference "C104") (unit 1)
        )
      )
    )
  )

  (symbol (lib_id "antmicropower:GND") (at 39.37 200.66 0) (mirror y) (unit 1)
    (in_bom yes) (on_board yes) (dnp no)
    (property "Reference" "#PWR0132" (at 39.37 207.01 0)
      (effects (font (size 1.27 1.27)) hide)
    )
    (property "Value" "GND" (at 41.275 205.105 0)
      (effects (font (size 1.27 1.27) (thickness 0.15)) (justify left bottom))
    )
    (property "Footprint" "" (at 39.37 200.66 0)
      (effects (font (size 1.27 1.27) (thickness 0.15)) (justify left bottom) hide)
    )
    (property "Datasheet" "" (at 39.37 200.66 0)
      (effects (font (size 1.27 1.27) (thickness 0.15)) (justify left bottom) hide)
    )
    (property "Author" "Antmicro" (at 30.48 208.28 0)
      (effects (font (size 1.27 1.27) (thickness 0.15)) (justify left bottom) hide)
    )
    (property "License" "Apache-2.0" (at 30.48 210.82 0)
      (effects (font (size 1.27 1.27) (thickness 0.15)) (justify left bottom) hide)
    )
    (pin "1")
    (instances
      (project "thunderbolt-pcie-adapter"
        (path ""
          (reference "#PWR0132") (unit 1)
        )
      )
    )
  )

  (symbol (lib_id "antmicroResistors0402:R_2k2_0402") (at 43.18 250.19 0) (unit 1)
    (in_bom yes) (on_board yes) (dnp no)
    (property "Reference" "R61" (at 41.275 248.92 0)
      (effects (font (size 1.27 1.27) (thickness 0.15)))
    )
    (property "Value" "R_2k2_0402" (at 63.5 262.89 0)
      (effects (font (size 1.27 1.27) (thickness 0.15)) (justify left bottom) hide)
    )
    (property "Footprint" "antmicro-footprints:R_0402_1005Metric" (at 63.5 265.43 0)
      (effects (font (size 1.27 1.27) (thickness 0.15)) (justify left bottom) hide)
    )
    (property "Datasheet" "https://www.bourns.com/docs/product-datasheets/cr.pdf" (at 63.5 267.97 0)
      (effects (font (size 1.27 1.27) (thickness 0.15)) (justify left bottom) hide)
    )
    (property "MPN" "CR0402-FX-2201GLF" (at 63.5 270.51 0)
      (effects (font (size 1.27 1.27) (thickness 0.15)) (justify left bottom) hide)
    )
    (property "Manufacturer" "Bourns" (at 63.5 273.05 0)
      (effects (font (size 1.27 1.27) (thickness 0.15)) (justify left bottom) hide)
    )
    (property "License" "Apache-2.0" (at 63.5 275.59 0)
      (effects (font (size 1.27 1.27) (thickness 0.15)) (justify left bottom) hide)
    )
    (property "Val" "2k2" (at 48.26 249.555 0)
      (effects (font (size 1.27 1.27) (thickness 0.15)) (justify left bottom))
    )
    (property "Tolerance" "1%" (at 63.5 260.35 0)
      (effects (font (size 1.27 1.27)) (justify left bottom) hide)
    )
    (property "Author" "Antmicro" (at 63.5 278.13 0)
      (effects (font (size 1.27 1.27) (thickness 0.15)) (justify left bottom) hide)
    )
    (pin "1")
    (pin "2")
    (instances
      (project "thunderbolt-pcie-adapter"
        (path ""
          (reference "R61") (unit 1)
        )
      )
    )
  )

  (symbol (lib_id "antmicroResistors0402:R_499R_0402") (at 134.62 96.52 0) (unit 1)
    (in_bom yes) (on_board yes) (dnp no)
    (property "Reference" "R73" (at 133.35 95.25 0)
      (effects (font (size 1.27 1.27) (thickness 0.15)))
    )
    (property "Value" "R_499R_0402" (at 154.94 109.22 0)
      (effects (font (size 1.27 1.27) (thickness 0.15)) (justify left bottom) hide)
    )
    (property "Footprint" "antmicro-footprints:R_0402_1005Metric" (at 154.94 111.76 0)
      (effects (font (size 1.27 1.27) (thickness 0.15)) (justify left bottom) hide)
    )
    (property "Datasheet" "https://www.mouser.com/datasheet/2/54/cr-1858361.pdf" (at 154.94 114.3 0)
      (effects (font (size 1.27 1.27) (thickness 0.15)) (justify left bottom) hide)
    )
    (property "MPN" "CR0402-FX-4990GLF" (at 154.94 116.84 0)
      (effects (font (size 1.27 1.27) (thickness 0.15)) (justify left bottom) hide)
    )
    (property "Manufacturer" "Bourns" (at 154.94 119.38 0)
      (effects (font (size 1.27 1.27) (thickness 0.15)) (justify left bottom) hide)
    )
    (property "License" "Apache-2.0" (at 154.94 121.92 0)
      (effects (font (size 1.27 1.27) (thickness 0.15)) (justify left bottom) hide)
    )
    (property "Val" "499R" (at 139.7 95.885 0)
      (effects (font (size 1.27 1.27) (thickness 0.15)) (justify left bottom))
    )
    (property "Tolerance" "1%" (at 154.94 106.68 0)
      (effects (font (size 1.27 1.27)) (justify left bottom) hide)
    )
    (property "Author" "Antmicro" (at 154.94 124.46 0)
      (effects (font (size 1.27 1.27) (thickness 0.15)) (justify left bottom) hide)
    )
    (pin "1")
    (pin "2")
    (instances
      (project "thunderbolt-pcie-adapter"
        (path ""
          (reference "R73") (unit 1)
        )
      )
    )
  )

  (symbol (lib_id "antmicroResistors0402:R_2k2_0402") (at 43.18 199.39 0) (unit 1)
    (in_bom yes) (on_board yes) (dnp no)
    (property "Reference" "R59" (at 40.64 198.12 0)
      (effects (font (size 1.27 1.27) (thickness 0.15)))
    )
    (property "Value" "R_2k2_0402" (at 63.5 212.09 0)
      (effects (font (size 1.27 1.27) (thickness 0.15)) (justify left bottom) hide)
    )
    (property "Footprint" "antmicro-footprints:R_0402_1005Metric" (at 63.5 214.63 0)
      (effects (font (size 1.27 1.27) (thickness 0.15)) (justify left bottom) hide)
    )
    (property "Datasheet" "https://www.bourns.com/docs/product-datasheets/cr.pdf" (at 63.5 217.17 0)
      (effects (font (size 1.27 1.27) (thickness 0.15)) (justify left bottom) hide)
    )
    (property "MPN" "CR0402-FX-2201GLF" (at 63.5 219.71 0)
      (effects (font (size 1.27 1.27) (thickness 0.15)) (justify left bottom) hide)
    )
    (property "Manufacturer" "Bourns" (at 63.5 222.25 0)
      (effects (font (size 1.27 1.27) (thickness 0.15)) (justify left bottom) hide)
    )
    (property "License" "Apache-2.0" (at 63.5 224.79 0)
      (effects (font (size 1.27 1.27) (thickness 0.15)) (justify left bottom) hide)
    )
    (property "Val" "2k2" (at 47.625 198.755 0)
      (effects (font (size 1.27 1.27) (thickness 0.15)) (justify left bottom))
    )
    (property "Tolerance" "1%" (at 63.5 209.55 0)
      (effects (font (size 1.27 1.27)) (justify left bottom) hide)
    )
    (property "Author" "Antmicro" (at 63.5 227.33 0)
      (effects (font (size 1.27 1.27) (thickness 0.15)) (justify left bottom) hide)
    )
    (pin "1")
    (pin "2")
    (instances
      (project "thunderbolt-pcie-adapter"
        (path ""
          (reference "R59") (unit 1)
        )
      )
    )
  )
)
